P  JOB   G:/<user>/TO/9052_F0T_PDB_Converter_Brick_F_V03_1208_1600.brd             
P  CODE  00                                                                     
P  UNITS CUST 0                                                                 
P  TITLE G:/<user>/TO/9052_F0T_PDB_Converter_Brick_F_V03_1208_1600.brd             
P  NUM   001                                                                    
P  REV   A                                                                      
P  VER IPC-D-356A                                                               
C                                                                               
C  IPC-D-356 Ouptut File from Allegro                                           
C  IPC File Date: Mon Dec 12 13:12:49 2022                                      
C                                                                               
C                                                                               
C  Board File:             9052_F0T_PDB_Converter_Brick_F_V03_1208_1600.brd     
C  Design Rule Status:     UP TO DATE                                           
C  Unit of Measure:        mils                                                 
C  Decimal Place Accuracy: 2                                                    
C  Number of etch Layers:  10                                                   
C  Board Thickness(mils):  92.900000                                            
C  Drawing Extents(mils):  -1000000  -2000000  9000000  8000000                 
C                                                                               
C                                                                               
C  BOARD LAYER INFORMATION                                                      
C                                                                               
C     Layer      Layer            Layer             Film  Layer                 
C     Name       Material         Type              Type  Number                
C  ---------------------------------------------------------                    
C  TOP           COPPER           CONDUCTOR         POS     1                   
C  GND           COPPER           PLANE             NEG     2                   
C  IN1           COPPER           CONDUCTOR         POS     3                   
C  GND1          COPPER           PLANE             NEG     4                   
C  VCC           COPPER           PLANE             NEG     5                   
C  VCC1          COPPER           PLANE             NEG     6                   
C  GND2          COPPER           PLANE             NEG     7                   
C  IN2           COPPER           CONDUCTOR         POS     8                   
C  GND3          COPPER           PLANE             NEG     9                   
C  BOTTOM        COPPER           CONDUCTOR         POS    10                   
C                                                                               
C                                                                               
C  PADSTACK INFORMATION                                                         
C                                                                               
C     Padstack          First     Last                                          
C     Name              Layer     Layer     Width     Height                    
C  ---------------------------------------------------------                    
C  C315D167B315I237_NPT TOP       BOTTOM        31900     31900                 
C  VIA18D10A26_BGA      TOP       BOTTOM         2600      2600                 
C  SMD26X54             TOP       TOP            3000      5800                 
C  SMD37X50_CUT         TOP       TOP            4042      5322                 
C  SMD10X50             TOP       TOP            1400      5400                 
C  SMD10X32             TOP       TOP            1400      3600                 
C  SMD10X34_CUT         TOP       TOP            1384      3746                 
C  SMD22X32             TOP       TOP            2600      3600                 
C  SMD60X126_CUT        TOP       TOP           12998      6306                 
C  SMD32X34             TOP       TOP            3600      3800                 
C  SMD15X46             TOP       TOP            1900      5000                 
C  SMD144X213_CUT       TOP       TOP           14770     21660                 
C  SMD11X28             TOP       TOP            1500      3200                 
C  SMD11X30             TOP       TOP            1500      3400                 
C  SMD18X20             TOP       TOP            2200      2400                 
C  SMD84-8X130          TOP       TOP            8880     13400                 
C  SMD16X44             TOP       TOP            2000      4800                 
C  SMD67X99             TOP       TOP            7100     10300                 
C  SMD85X89             TOP       TOP            8900      9300                 
C  S62D42               TOP       BOTTOM         7200      7200                 
C  C62D42               TOP       BOTTOM         7200      7200                 
C  S60D40               TOP       BOTTOM         7000      7000                 
C  C60D40               TOP       BOTTOM         7000      7000                 
C  SMD116X197           TOP       TOP           12000     20100                 
C  SMD126X270           TOP       TOP           13000     27400                 
C  RE-R_0824-2          TOP       TOP            2384      2368                 
C  RE-L_0824-2          TOP       TOP            2384      2368                 
C  C237D156N_V196_ANT23 TOP       BOTTOM        24100     24100                 
C  C156D156N            TOP       BOTTOM        18600     18600                 
C  SMD128X135           TOP       TOP           13200     13900                 
C  C125D125N_T2-0       TOP       BOTTOM        15500     15500                 
C  C85D67_SM85_NPM      TOP       BOTTOM         9700      9700                 
C  SMD17X24             TOP       TOP            2100      2800                 
C  SMD14X59             TOP       TOP            1800      6300                 
C  SMD18X52             TOP       TOP            2200      5600                 
C  SMD22X68             TOP       TOP            2600      7200                 
C  SMD14X56             TOP       TOP            1800      6000                 
C  SMD40X63             TOP       TOP            4400      6700                 
C  SMD32X36             TOP       TOP            3600      4000                 
C  SH10X28_CUT_R        TOP       TOP            1384      3156                 
C  SMD10X52             TOP       TOP            1400      5600                 
C  SMD10X36             TOP       TOP            1400      4000                 
C  SH10X28_CUT_L        TOP       TOP            1384      3156                 
C  C93D63               TOP       BOTTOM         9700      9700                 
C  S93D63               TOP       BOTTOM         9700      9700                 
C  C52D36               TOP       BOTTOM         6600      6600                 
C  C123D83              TOP       BOTTOM        12700     12700                 
C  SMD110X220           TOP       TOP           11400     22400                 
C  SMD59X134            TOP       TOP            6300     13800                 
C  SMDOB12X33_SM14X37   TOP       TOP            1400      3700                 
C  SMD44X54             TOP       TOP            4800      5800                 
C  SMD10X20             TOP       TOP            1400      2400                 
C  SMD52X122_PM48X119_C TOP       TOP            5600     12600                 
C  SH8-45X10-6_PM8-35X1 TOP       TOP           33668     42132                 
C  SH28X32_NPM          TOP       TOP            3200      7600                 
C  SMD28X32_NPM         TOP       TOP            3200      3600                 
C  SMD99X130            TOP       TOP           10300     13400                 
C  SMD95X130            TOP       TOP            9900     13400                 
C  SMD28X32             TOP       TOP            3200      3600                 
C  SMD46X62             TOP       TOP            5000      6600                 
C  SMD40X50             TOP       TOP            4400      5400                 
C  C66D46               TOP       BOTTOM         7600      7600                 
C  S66D46               TOP       BOTTOM         7600      7600                 
C  C58D41               TOP       BOTTOM         7100      7100                 
C  S50D34               TOP       BOTTOM         6400      6400                 
C  C50D34               TOP       BOTTOM         6400      6400                 
C  C87D87N              TOP       BOTTOM        11700     11700                 
C  S60-15D40-15_FIT     TOP       BOTTOM         6415      6415                 
C  C60-15D40-15_FIT     TOP       BOTTOM         6415      6415                 
C  C256D126N_V166_ANT25 TOP       BOTTOM        26000     26000                 
C  C400D252B394X1260_IY TOP       BOTTOM        40400    126700                 
C  OB394X1260D119_197Y4 TOP       BOTTOM        39800    126400                 
C  SMD24X28             TOP       TOP            2800      3200                 
C  VT20D10T30           TOP       BOTTOM         7502      7500                 
C  VT20D10B26           TOP       BOTTOM         7502      7500                 
C  VIA20D10             TOP       BOTTOM         3000      3000                 
C  SPD_C125                                     12500     12500                 
C  SMDC39M118           TOP       TOP           11800     11800                 
C  TP26B                BOTTOM    BOTTOM         7500      7500                 
C  TP30T                TOP       TOP            7500      7500                 
C                                                                               
C                                                                               
C  ****************************************                                     
C     Name mapping for long Signal names                                        
C  ****************************************                                     
C                                                                               
P  NNAMEm0000 FM_AC_PWR_CYCLE_R_BUF                                             
P  NNAMEm0001 FM_AC_PWR_CYCLE_R_N                                               
P  NNAMEm0002 FM_AC_PWR_CYCLE_R1_N                                              
P  NNAMEm0003 P12V_HPDB_0_ISET_R                                                
P  NNAMEm0004 P52V_HS1_EN_BUF_DELAY                                             
P  NNAMEm0005 P52V_HS1_EN_DELAY_N                                               
P  NNAMEm0006 FM_AC_PWR_CYCLE_BUF                                               
P  NNAMEm0007 FM_AC_PWR_CYCLE_N                                                 
P  NNAMEm0008 P52V_HS1_EN_DELAY                                                 
P  NNAMEm0009 PWRGD_P3V3_HPDB                                                   
P  NNAMEm0010 P12V_HPDB_0_FLTB                                                  
P  NNAMEm0011 P12V_HPDB_0_IMON                                                  
P  NNAMEm0012 P12V_HPDB_0_ISET                                                  
P  NNAMEm0013 P12V_HPDB_0_TIMER                                                 
P  NNAMEm0014 P12V_HPDB_0_EN_R                                                  
P  NNAMEm0015 FM_HSC_EN_BUSBAR                                                  
P  NNAMEm0016 SMB_P52V_HSC_SDA                                                  
P  NNAMEm0017 SMB_P52V_HSC_SCL                                                  
P  NNAMEm0018 SMB_P52V_VPDB_SCL_R3                                              
P  NNAMEm0019 P52V_HS1_TEMPN_R                                                  
P  NNAMEm0020 P52V_HS1_TEMP_R                                                   
P  NNAMEm0021 P52V_HS1_1272_GATE                                                
P  NNAMEm0022 P52V_HS_1272_S_N                                                  
P  NNAMEm0023 P52V_HS_1272_S_P                                                  
P  NNAMEm0024 P52V_HS1_DRAIN_2                                                  
P  NNAMEm0025 P52V_HS1_DRAIN_1                                                  
P  NNAMEm0026 P52V_HS_4287_S2N                                                  
P  NNAMEm0027 P52V_HS_4287_S2P                                                  
P  NNAMEm0028 P52V_HS_4287_ADC_N                                                
P  NNAMEm0029 P52V_HS_4287_ADC_P                                                
P  NNAMEm0030 P52V_HS_4287_S1N                                                  
P  NNAMEm0031 P52V_HS_4287_S1P                                                  
P  NNAMEm0032 P52V_HS1_4287_GATE_R                                              
P  NNAMEm0033 P52V_HS1_GATE2_R1                                                 
P  NNAMEm0034 P52V_HS1_GATE2_R                                                  
P  NNAMEm0035 P52V_HS1_GATE1_R                                                  
P  NNAMEm0036 P52V_HS1_4287_GATE2_RC                                            
P  NNAMEm0037 P52V_HS1_4287_GATE2_R                                             
P  NNAMEm0038 P52V_HS1_GATE_RC                                                  
P  NNAMEm0039 PWRGD_P52V_HS1_PG_N                                               
P  NNAMEm0040 SMB_P52V_HS1_SDAO                                                 
P  NNAMEm0041 SMB_P52V_HS1_SDAI                                                 
P  NNAMEm0042 P52V_HS1_GATE_R1                                                  
P  NNAMEm0043 GND_FIELD_SIGNAL                                                  
P  NNAMEm0044 P52V_HS1_INTVCC                                                   
P  NNAMEm0045 SW_P12V_FILT__P3V3_AUX                                            
P  NNAMEm0046 SW_P3V3_AUX_BT_R                                                  
P  NNAMEm0047 P12V_BRICK3_ALERT_N                                               
P  NNAMEm0048 P12V_BRICK0_PWRGD                                                 
P  NNAMEm0049 BRICK_P12V_1_EN_N                                                 
P  NNAMEm0050 BRICK_P12V_EN_R_N                                                 
P  NNAMEm0051 P12V_BRICK_PWRGD_N                                                
P  NNAMEm0052 P12V_HPDB_PWRGD                                                   
P  NNAMEm0053 P12V_MB3_SENSE+                                                   
P  NNAMEm0054 P12V_MB2_SENSE-                                                   
P  NNAMEm0055 BRICK_P12V2_ON_OFF_R                                              
P  NNAMEm0056 SMB_BRICK2_ALERT                                                  
P  NNAMEm0057 PWRGD_GPU_HSC_R                                                   
P  NNAMEm0058 PWRGD_GPU_HSC_BUF_R                                               
P  NNAMEm0059 SMB_P52V_VPDB_SCL_R                                               
P  NNAMEm0060 PWRGD_P3V3_AUX_MB_BUF_N                                           
P  NNAMEm0061 PWRGD_P3V3_AUX_MB_BUF                                             
P  NNAMEm0062 PWRGD_P3V3_AUX_MB_BUF_R                                           
P  NNAMEm0063 PWRGD_P3V3_AUX_MB_R1                                              
P  NNAMEm0064 PWRGD_P3V3_AUX_MB_R                                               
P  NNAMEm0065 PWRGD_P3V3_AUX_MB                                                 
P  NNAMEm0066 SMB_P52V_VPDB_SCL_R2                                              
P  NNAMEm0067 SMB_VPDB_IOEXP_SCL                                                
P  NNAMEm0068 SMB_VPDB_IOEXP_SDA                                                
P  NNAMEm0069 SMB_P52V_VPDB_SCL                                                 
P  NNAMEm0070 SMB_HPDB_MISC_SDA                                                 
P  NNAMEm0071 SMB_VPDB_MISC_SDA                                                 
P  NNAMEm0072 SMB_HPDB_MISC_SCL                                                 
P  NNAMEm0073 SMB_VPDB_MISC_SCL                                                 
P  NNAMEm0074 SMB_P52V_HPDB_SCL                                                 
P  NNAMEm0075 SMB_P52V_HPDB_SDA                                                 
P  NNAMEm0076 SMB_P52V_VPDB_SDA                                                 
P  NNAMEm0077 P52V_HS1_SENSE_P_R2                                               
P  NNAMEm0078 P52V_HS1_SENSE_N_R2                                               
P  NNAMEm0079 RST_SMB_PDB_BUF_R1_N                                              
P  NNAMEm0080 PCA9543_MISC_A0                                                   
P  NNAMEm0081 PCA9543_MISC_A1                                                   
P  NNAMEm0082 TP_9543_MISC_INT_N                                                
P  NNAMEm0083 P12V_BRICK_PWRGD_R_N                                              
P  NNAMEm0084 TDR_SE_50_OHM_IN2                                                 
P  NNAMEm0085 TDR_SE_50_OHM_BOT                                                 
P  NNAMEm0086 TDR_SE_50_OHM_IN1                                                 
P  NNAMEm0087 TDR_SE_50_OHM_TOP                                                 
P  NNAMEm0088 FAN_PWR_EN_BUF_R                                                  
P  NNAMEm0089 SMB_MB_PDB_R_SDA                                                  
P  NNAMEm0090 SMB_MB_PDB_R_SCL                                                  
P  NNAMEm0091 P12V_MB1_SENSE+                                                   
P  NNAMEm0092 SMB_BRICK1_ALERT                                                  
P  NNAMEm0093 P12V_MB1_SENSE-                                                   
P  NNAMEm0094 BRICK_P12V1_ON_OFF_R                                              
P  NNAMEm0095 P12V_BRICK2_ALERT_N                                               
P  NNAMEm0096 SMB_HPDB_MISC_R_SDA                                               
P  NNAMEm0097 SMB_HPDB_MISC_R_SCL                                               
P  NNAMEm0098 P12V_BRICK1_ALERT_N                                               
P  NNAMEm0099 PWRGD_GPU_HSC_BUF                                                 
P  NNAMEm0100 P3V3_AUX_SCALED                                                   
P  NNAMEm0101 SMB_P52V_HPDB_R_SCL                                               
P  NNAMEm0102 SMB_P52V_HPDB_R_SDA                                               
P  NNAMEm0103 P52V_HS1_EFAULT                                                   
P  NNAMEm0104 P52V_HS1_ESTART                                                   
P  NNAMEm0105 P52V_HS1_ISTART                                                   
P  NNAMEm0106 P52V_HS1_EFAULT_R                                                 
P  NNAMEm0107 P52V_HS1_ESTART_R                                                 
P  NNAMEm0108 SMB_CM_HS1_3V3SB_DATO                                             
P  NNAMEm0109 P52V_HS1_SENSE_P_R1                                               
P  NNAMEm0110 P52V_HS1_SENSE_N_R1                                               
P  NNAMEm0111 P12V_MB2_SENSE+                                                   
P  NNAMEm0112 SMB_CM_HS1_3V3SB_DATI                                             
P  NNAMEm0113 BRICK_P12V3_ON_OFF_R                                              
P  NNAMEm0114 P12V_MB3_SENSE-                                                   
P  NNAMEm0115 PWRGD_P52V_HS1_PG                                                 
P  NNAMEm0116 SMB_P52V_VPDB_DEBUG_SDA                                           
P  NNAMEm0117 SMB_BRICK3_ALERT                                                  
P  NNAMEm0118 SMB_P52V_VPDB_DEBUG_SCL                                           
P  NNAMEm0119 P12V_BRICK0_ALERT_N                                               
P  NNAMEm0120 RST_SMB_PDB_R_N                                                   
P  NNAMEm0121 P52V_HS1_DV_DT_R                                                  
P  NNAMEm0122 P52V_HS1_PWRGIN                                                   
P  NNAMEm0123 P52V_HS1_UVLO_EN                                                  
P  NNAMEm0124 P12V_BRICK_PWRGD                                                  
P  NNAMEm0125 BRICK_P12V0_EN_N                                                  
P  NNAMEm0126 SMB_BRICK0_ALERT                                                  
P  NNAMEm0127 P12V_MB0_SENSE+                                                   
P  NNAMEm0128 RST_SMB_PDB_BUF_N                                                 
P  NNAMEm0129 BRICK_P12V0_EN_R_N                                                
P  NNAMEm0130 RST_SMB_PDB_BUF_R_N                                               
P  NNAMEm0131 BRICK_P12V0_ON_OFF_R                                              
P  NNAMEm0132 P12V_MB0_SENSE-                                                   
P  NNAMEm0133 SMB_PDB_MISC_SDA                                                  
P  NNAMEm0134 SMB_PDB_MISC_SCL                                                  
P  NNAMEm0135 SMB_PDB_MISC_SDA_R                                                
P  NNAMEm0136 SMB_PDB_MISC_SCL_R                                                
C                                                                               
C  ****************************************                                     
C      SIGNAL PINS & VIAS ON THE BOARD                                          
C  ****************************************                                     
C                                                                               
327TP_U4_P06        U4    -10         A10X+084296Y+031100X0140Y0590R180 S2      
317TP_U4_P06        VIA   -           A01X+084500Y+030300X0300Y         S1      
017TP_U4_P06        VIA   -           A10X+084500Y+030300X0200Y         S1      
017TP_U4_P06              -     D0100PA00X+084500Y+030300                       
327TP_U4_P05        VIA   -           A10X+084260Y+031760X0260Y         S2      
327TP_U4_P05        U4    -9          A10X+084040Y+031100X0140Y0590R180 S2      
327m0000            D11   -A          A10X+110013Y+010700X0670Y0990R090 S2      
327m0000            VIA   -    M      A10X+108530Y+011402X0260Y         S2      
327m0000            U37   -G          A10X+107376Y+010844X0320Y0360R180 S2      
327m0000            C102  -1   M      A10X+107358Y+011400X0198Y0197     S2      
327m0000            R5917 -2   M      A10X+107750Y+011392X0198Y0197R090 S2      
317m0001            VIA   -    MD0100PA00X+086360Y+020890X0200Y         S0      
317m0001            VIA   -    MD0100PA00X+105383Y+019167X0200Y         S0      
327m0001            R5904 -2          A10X+113200Y+018058X0198Y0197R270 S2      
317m0001            J1    -A2   D0402PA00X+082256Y+014941X0602Y    R270 S3      
327m0001            VIA   -    M      A10X+084300Y+016700X0260Y         S2      
327m0002            R5919 -2          A10X+114087Y+014373X0198Y0197R180 S2      
327m0002            D6    -2   M      A10X+114402Y+014973X0260Y0540R090 S2      
327m0002            U36   -G          A10X+115244Y+014174X0320Y0360R090 S2      
327m0002            VIA   -    M      A10X+115042Y+014740X0260Y         S2      
327m0002            C100  -1   M      A10X+115042Y+015400X0198Y0197R180 S2      
327m0003            R5902 -2          A10X+018148Y+022772X0198Y0197R180 S2      
327m0003            C98   -1          A10X+018145Y+022352X0198Y0197     S2      
327m0003            VIA   -    M      A10X+018595Y+022608X0260Y    R270 S2      
327m0004            R5932 -2          A01X+108977Y+013954X0440Y0540R270 S1      
317m0004            VIA   -    MD0100PA00X+108440Y+015926X0200Y         S0      
327m0004            VIA   -    M      A10X+109850Y+015694X0260Y         S2      
327m0004            PU1   -23         A01X+105194Y+015981X0110Y0300R270 S1      
317m0004            VIA   -    MD0100PA00X+106350Y+015981X0200Y         S0      
327m0004            PU7   -6          A01X+111652Y+016768X0120Y0330R270 S1      
317m0004            VIA   -    MD0100PA00X+110882Y+016680X0200Y         S0      
327m0004            U40   -D   M      A10X+108800Y+015694X0320Y0360     S2      
327m0004            R5933 -1   M      A10X+106750Y+015958X0198Y0197R090 S2      
327m0005            VIA   -    M      A10X+110200Y+014800X0260Y         S2      
327m0005            U39   -D          A10X+110606Y+015450X0320Y0360R090 S2      
327m0005            R5931 -1   M      A10X+110450Y+014308X0198Y0197R090 S2      
327m0005            R5930 -2   M      A10X+109124Y+013500X0440Y0540     S2      
327m0005            U40   -G          A10X+109174Y+014906X0320Y0360     S2      
327m0006            R5915 -2   M      A10X+111050Y+011726X0440Y0540R270 S2      
327m0006            D11   -C   M      A10X+111587Y+010700X0670Y0990R090 S2      
327m0006            VIA   -    M      A10X+109550Y+011708X0260Y         S2      
327m0006            R5917 -1          A10X+107750Y+011708X0198Y0197R090 S2      
327m0006            R5916 -1          A10X+114150Y+011442X0198Y0197R270 S2      
327m0006            U36   -D          A10X+114456Y+013800X0320Y0360R090 S2      
327m0007            R5911 -1          A10X+114676Y+017140X0198Y0197R090 S2      
327m0007            VIA   -    M      A10X+113148Y+016929X0260Y         S2      
327m0007            R5919 -1          A10X+113772Y+014373X0198Y0197R180 S2      
327m0007            D6    -1   M      A10X+113457Y+014973X0260Y0540R270 S2      
327m0007            R5910 -2   M      A10X+114676Y+017700X0440Y0540R180 S2      
327m0007            R5904 -1   M      A10X+113200Y+017742X0198Y0197R270 S2      
327m0008            R5918 -2   M      A10X+104976Y+011150X0440Y0540R180 S2      
327m0008            D12   -A          A10X+104613Y+010050X0670Y0990R090 S2      
327m0008            VIA   -    M      A10X+104350Y+011150X0260Y         S2      
327m0008            U39   -G          A10X+111394Y+015824X0320Y0360R090 S2      
327m0008            C101  -1   M      A10X+106350Y+011750X0400Y0500R090 S2      
327m0009            VIA   -    M      A10X+017940Y+032680X0260Y         S2      
317m0009            VIA   -    MD0100PA00X+081450Y+029300X0200Y         S0      
327m0009            U4    -13         A10X+084808Y+028800X0140Y0590R180 S2      
317m0009            VIA   -    MD0100PA00X+079380Y+032388X0200Y         S0      
317m0009            J7    -S2   D0340PA00X+003878Y+031972X0500Y    R270 S3      
317PRSNT_HPDB_N     VIA   -    MD0100PA00X+080650Y+028550X0200Y         S0      
327PRSNT_HPDB_N     R5909 -2   M      A10X+080650Y+028258X0198Y0197R270 S2      
327PRSNT_HPDB_N     U4    -14         A10X+084552Y+028800X0140Y0590R180 S2      
327PRSNT_HPDB_N     VIA   -    M      A10X+081100Y+028600X0260Y         S2      
317PRSNT_HPDB_N     VIA   -    MD0100PA00X+078650Y+031670X0200Y         S0      
317PRSNT_HPDB_N     J7    -S1   D0340PA00X+003378Y+031472X0500Y0500R270 S3      
327P12V_HPDB_0_PD   VIA   -           A01X+014166Y+023957X0300Y    R270 S1      
327P12V_HPDB_0_PD   R5893 -2   M      A01X+014184Y+023490X0180Y0200R270 S1      
327P12V_HPDB_0_PD   R5895 -2          A01X+014700Y+023540X0280Y0320R180 S1      
327P12V_HPDB_0_PD   U32   -12         A01X+015859Y+023407X0100Y0320R090 S1      
327P12V_HPDB_0_PD   C95   -2          A01X+015220Y+023540X0280Y0320R180 S1      
327P12V_HPDB_0_FB   R5894 -2   M      A01X+016213Y+024516X0180Y0200R180 S1      
327P12V_HPDB_0_FB   R5896 -2          A01X+016213Y+024914X0180Y0200R180 S1      
327P12V_HPDB_0_FB   R5899 -2   M      A01X+016213Y+024114X0198Y0197     S1      
327P12V_HPDB_0_FB   U32   -11         A01X+016213Y+023565X0100Y0320R180 S1      
317P12V_HPDB_0_FB   VIA   -    M      A01X+016002Y+023776X0200Y    R270 S2      
017P12V_HPDB_0_FB   VIA   -    M      A10X+016002Y+023776X0260Y    R270 S2      
017P12V_HPDB_0_FB         -    MD0100PA00X+016002Y+023776                       
327m0010            U32   -9          A01X+016961Y+023407X0100Y0320R090 S1      
327m0010            VIA   -           A01X+017137Y+025192X0300Y    R270 S1      
327m0010            R5897 -1   M      A01X+017004Y+024226X0198Y0197R090 S1      
327m0011            R5900 -1   M      A01X+017826Y+024233X0198Y0197     S1      
327m0011            C97   -1   M      A01X+017826Y+023833X0198Y0197     S1      
327m0011            U32   -8          A01X+016961Y+023211X0100Y0320R090 S1      
327m0011            VIA   -           A01X+017826Y+024771X0300Y    R270 S1      
327m0012            R5901 -1          A01X+017832Y+022482X0198Y0197     S1      
327m0012            R5902 -1          A10X+017833Y+022772X0198Y0197R180 S2      
327m0012            U32   -5          A01X+016961Y+022620X0100Y0320R090 S1      
327m0012            VIA   -    M      A10X+017833Y+023290X0260Y    R270 S2      
317m0012            VIA   -    MD0100PA00X+017548Y+022518X0200Y    R270 S0      
327P12V_HPDB_0_SS   C96   -1          A01X+017826Y+023133X0198Y0197     S1      
327P12V_HPDB_0_SS   U32   -6          A01X+016961Y+022817X0100Y0320R090 S1      
317P12V_HPDB_0_SS   VIA   -    M      A01X+017387Y+022817X0200Y    R270 S2      
017P12V_HPDB_0_SS   VIA   -    M      A10X+017387Y+022817X0260Y    R270 S2      
017P12V_HPDB_0_SS         -    MD0100PA00X+017387Y+022817                       
327m0013            C94   -1          A01X+017826Y+022083X0198Y0197     S1      
327m0013            U32   -4          A01X+016961Y+022423X0100Y0320R090 S1      
317m0013            VIA   -    M      A01X+017598Y+021878X0200Y    R270 S2      
017m0013            VIA   -    M      A10X+017598Y+021878X0260Y    R270 S2      
017m0013                  -    MD0100PA00X+017598Y+021878                       
327m0014            R5892 -2   M      A01X+017826Y+021683X0198Y0197R180 S1      
327m0014            U32   -1          A01X+016951Y+021833X0098Y0335R090 S1      
317m0014            VIA   -           A01X+017826Y+021344X0200Y    R270 S2      
017m0014            VIA   -           A10X+017826Y+021344X0260Y    R270 S2      
017m0014                  -     D0100PA00X+017826Y+021344                       
327P52V_HS1_R_EN    VIA   -    M      A01X+109450Y+010300X0300Y         S1      
327P52V_HS1_R_EN    PR6973-2          A01X+108958Y+010300X0198Y0197     S1      
327P52V_HS1_R_EN    U19   -4          A01X+110028Y+010124X0220Y0320R090 S1      
327P52V_1_R         R5932 -1          A01X+108977Y+013206X0440Y0540R270 S1      
317P52V_1_R         VIA   -    MD0100PA00X+116760Y+018050X0200Y         S0      
317P52V_1_R         VIA   -    MD0100PA00X+116760Y+018450X0200Y         S0      
327P52V_1_R         VIA   -    M      A10X+102434Y+013950X0260Y         S2      
327P52V_1_R         PC3   -1          A01X+102500Y+014280X0460Y0620R090 S1      
327P52V_1_R         PU1   -10         A01X+102773Y+014928X0110Y0280     S1      
317P52V_1_R         VIA   -    MD0100PA00X+102434Y+014660X0200Y         S0      
327P52V_1_R         R5890 -2          A10X+116760Y+018956X0440Y0540R270 S2      
317P52V_1_R         VIA   -    MD0100PA00X+107720Y+009090X0200Y         S0      
327P52V_1_R         R5889 -1          A01X+107596Y+009540X0440Y0540R180 S1      
317P52V_1_R         VIA   -    MD0100PA00X+107320Y+009090X0200Y         S0      
317P52V_1_R         VIA   -    MD0100PA00X+115800Y+017900X0200Y         S0      
327P52V_1_R         R5910 -1          A10X+115424Y+017700X0440Y0540R180 S2      
327P52V_1_R         R5930 -1          A10X+108376Y+013500X0440Y0540     S2      
317P52V_1_R         VIA   -    MD0100PA00X+108432Y+013020X0200Y    R090 S0      
327P52V_1_R         R5915 -1          A10X+111050Y+012474X0440Y0540R270 S2      
317P52V_1_R         VIA   -    MD0100PA00X+111580Y+012660X0200Y    R180 S0      
327P3V3_AND         R5889 -2          A01X+108344Y+009540X0440Y0540R180 S1      
327P3V3_AND         VIA   -    M      A01X+109100Y+008900X0300Y         S1      
327P3V3_AND         R5888 -1   M      A01X+109100Y+009392X0198Y0197R090 S1      
327P3V3_AND         U19   -5          A01X+110028Y+009376X0220Y0320R090 S1      
327P3V3_AND         C90   -1   M      A01X+109510Y+009392X0198Y0197R090 S1      
317m0015            JP3   -1    D0460PA00X+115100Y+009040X0660Y0660     S3      
327m0015            VIA   -    M      A01X+112100Y+009450X0300Y         S1      
327m0015            C89   -1   M      A01X+111010Y+008300X0280Y0320R270 S1      
327m0015            U19   -1   M      A01X+110972Y+009376X0220Y0320R090 S1      
327m0015            R5885 -1   M      A01X+110992Y+008800X0198Y0197     S1      
327m0015            R5884 -2          A01X+110374Y+008250X0440Y0540R180 S1      
327FM_HSC_EN_FUSE   VIA   -    M      A01X+111550Y+009750X0300Y         S1      
317FM_HSC_EN_FUSE   JP3   -3   MD0460PA00X+117100Y+009040X0660Y         S3      
327FM_HSC_EN_FUSE   C69   -1   M      A01X+117060Y+010550X0280Y0320R270 S1      
327FM_HSC_EN_FUSE   R5886 -2          A01X+116600Y+014076X0440Y0540R090 S1      
327FM_HSC_EN_FUSE   R5887 -1   M      A01X+117192Y+011150X0198Y0197     S1      
327FM_HSC_EN_FUSE   U19   -2          A01X+110972Y+009750X0220Y0320R090 S1      
327m0016            PR92  -1          A01X+102258Y+009800X0198Y0197R180 S1      
317m0016            VIA   -    MD0100PA00X+102258Y+010092X0200Y    R270 S0      
317m0016            VIA   -    MD0100PA00X+105800Y+019150X0200Y         S0      
327m0016            R5855 -1   M      A01X+105800Y+018908X0198Y0197R270 S1      
327m0016            R5856 -1          A01X+105350Y+018908X0198Y0197R270 S1      
317m0016            VIA   -    M      A01X+109450Y+014314X0200Y         S2      
017m0016            VIA   -    M      A10X+109450Y+014314X0260Y         S2      
017m0016                  -    MD0100PA00X+109450Y+014314                       
327m0016            R147  -2          A01X+110004Y+015186X0198Y0197     S1      
327m0016            R145  -1   M      A01X+109696Y+014314X0198Y0197     S1      
327m0016            R144  -1   M      A01X+109692Y+014750X0198Y0197     S1      
317m0016            VIA   -    MD0100PA00X+073200Y+032600X0200Y         S0      
327m0016            R5879 -2          A10X+073192Y+032850X0198Y0197     S2      
327m0017            PR313 -1          A01X+102258Y+011800X0198Y0197R180 S1      
317m0017            VIA   -    MD0100PA00X+102258Y+011550X0200Y    R270 S0      
317m0017            VIA   -    M      A01X+106250Y+019150X0200Y         S2      
017m0017            VIA   -    M      A10X+106250Y+019150X0260Y         S2      
017m0017                  -    MD0100PA00X+106250Y+019150                       
327m0017            R5864 -1          A01X+106250Y+018908X0198Y0197R270 S1      
317m0017            VIA   -    MD0100PA00X+109200Y+015950X0200Y         S0      
327m0017            R81   -1          A01X+109689Y+016041X0198Y0197     S1      
317m0017            VIA   -    MD0100PA00X+073192Y+033600X0200Y         S0      
327m0017            R5878 -2          A10X+073192Y+033850X0198Y0197     S2      
317H25_TP           H25   -1    D1670PA00X+122602Y+017443X3150Y         S3      
317H24_TP           H24   -1    D1670PA00X+122602Y+039943X3150Y         S3      
327P52V_FAN         R5873 -4          A10X+012937Y+041450X0160Y0440R270 S2      
327P52V_FAN         VIA   -           A10X+012850Y+042600X0260Y         S2      
317P52V_FAN         J7    -P8  MD0410PA00X+003878Y+029929X0580Y    R270 S3      
317P52V_FAN         J7    -P7  MD0410PA00X+003878Y+029260X0580Y    R270 S3      
317P52V_FAN         J7    -P6  MD0410PA00X+003878Y+027929X0580Y    R270 S3      
317P52V_FAN         J7    -P5  MD0410PA00X+003878Y+027260X0580Y    R270 S3      
317P52V_FAN         VIA   -    MD0100PA00X+011570Y+042670X0200Y    R180 S0      
317P52V_FAN         VIA   -    MD0100PA00X+011570Y+042370X0200Y    R180 S0      
317P52V_FAN         VIA   -    MD0100PA00X+011950Y+042360X0200Y    R180 S0      
317P52V_FAN         VIA   -    MD0100PA00X+012300Y+042360X0200Y    R180 S0      
317P52V_FAN         VIA   -    MD0100PA00X+011950Y+042660X0200Y    R180 S0      
317P52V_FAN         VIA   -    MD0100PA00X+012300Y+042660X0200Y    R180 S0      
317P52V_FAN         VIA   -    MD0100PA00X+011570Y+041460X0200Y    R180 S0      
317P52V_FAN         VIA   -    MD0100PA00X+011570Y+041160X0200Y    R180 S0      
317P52V_FAN         VIA   -    MD0100PA00X+011570Y+040860X0200Y    R180 S0      
317P52V_FAN         VIA   -    MD0100PA00X+011570Y+041760X0200Y    R180 S0      
317P52V_FAN         VIA   -    MD0100PA00X+011570Y+042060X0200Y    R180 S0      
317P52V_FAN         J7    -P9  MD0410PA00X+004878Y+029929X0580Y    R270 S3      
317P52V_FAN         J7    -P10 MD0410PA00X+004878Y+029260X0580Y    R270 S3      
317P52V_FAN         J7    -P11 MD0410PA00X+004878Y+027929X0580Y    R270 S3      
317P52V_FAN         J7    -P12 MD0410PA00X+004878Y+027260X0580Y    R270 S3      
327P52V_FAN         R5873 -2          A10X+012543Y+041450X1260Y0591R270 S2      
317P52V_FAN         VIA   -    MD0100PA00X+012300Y+042050X0200Y    R180 S0      
317P52V_FAN         VIA   -    MD0100PA00X+011950Y+042050X0200Y    R180 S0      
317P52V_FAN         VIA   -    MD0100PA00X+012300Y+041750X0200Y    R180 S0      
317P52V_FAN         VIA   -    MD0100PA00X+011950Y+041750X0200Y    R180 S0      
317P52V_FAN         VIA   -    MD0100PA00X+012300Y+040850X0200Y    R180 S0      
317P52V_FAN         VIA   -    MD0100PA00X+011950Y+040850X0200Y    R180 S0      
317P52V_FAN         VIA   -    MD0100PA00X+012300Y+041150X0200Y    R180 S0      
317P52V_FAN         VIA   -    MD0100PA00X+011950Y+041150X0200Y    R180 S0      
317P52V_FAN         VIA   -    MD0100PA00X+011950Y+041450X0200Y    R180 S0      
317P52V_FAN         VIA   -    MD0100PA00X+012300Y+041450X0200Y    R180 S0      
327m0018            VIA   -    M      A01X+106250Y+018100X0300Y         S1      
327m0018            R5864 -2          A01X+106250Y+018592X0198Y0197R270 S1      
327m0018            PU1   -27         A01X+105194Y+016769X0110Y0300R270 S1      
327m0019            VIA   -           A01X+113500Y+022060X0300Y         S1      
327m0019            PR6969-1          A01X+111174Y+022424X0180Y0200     S1      
327m0019            PR6968-2   M      A01X+111174Y+022424X0180Y0200     S1      
327m0019            PQ15  -E   M      A01X+112157Y+022406X0400Y0500R270 S1      
327m0020            VIA   -           A01X+113660Y+022806X0300Y         S1      
327m0020            PR6966-2          A01X+111166Y+023174X0180Y0200R180 S1      
327m0020            PR6967-2   M      A01X+111166Y+023174X0180Y0200     S1      
327m0020            PQ15  -C   M      A01X+113037Y+022806X0400Y0500R270 S1      
327m0020            PQ15  -B   M      A01X+112157Y+023206X0400Y0500R270 S1      
327m0021            R5860 -2          A10X+107680Y+040692X0198Y0197R090 S2      
317m0021            VIA   -    MD0100PA00X+107432Y+040692X0200Y         S0      
327m0021            R5861 -1          A10X+108042Y+036344X0198Y0197     S2      
317m0021            VIA   -    MD0100PA00X+108042Y+037360X0200Y    R180 S0      
317m0021            VIA   -    M      A01X+115250Y+018650X0200Y         S2      
017m0021            VIA   -    M      A10X+115250Y+018650X0260Y         S2      
017m0021                  -    MD0100PA00X+115250Y+018650                       
327m0021            PU7   -32         A01X+114762Y+016965X0120Y0330R270 S1      
317m0022            VIA   -    MD0100PA00X+117950Y+047325X0200Y         S0      
327m0022            PR6958-1          A01X+117440Y+047125X0280Y0320R090 S1      
327m0022            PU7   -38         A01X+114290Y+018028X0120Y0330     S1      
317m0022            VIA   -    M      A01X+114349Y+018356X0200Y         S2      
017m0022            VIA   -    M      A10X+114349Y+018356X0260Y         S2      
017m0022                  -    MD0100PA00X+114349Y+018356                       
327m0022            PR6959-1          A01X+117431Y+032875X0280Y0320R090 S1      
317m0022            VIA   -    MD0100PA00X+117941Y+032725X0200Y    R180 S0      
327m0023            PR6960-1          A01X+118460Y+047125X0280Y0320R270 S1      
317m0023            VIA   -    M      A01X+117950Y+046975X0200Y    R180 S2      
017m0023            VIA   -    M      A10X+117950Y+046975X0260Y    R180 S2      
017m0023                  -    MD0100PA00X+117950Y+046975                       
327m0023            PU7   -39         A01X+114093Y+018028X0120Y0330     S1      
317m0023            VIA   -    MD0100PA00X+114034Y+018356X0200Y         S0      
327m0023            PR6961-1          A01X+118451Y+032875X0280Y0320R270 S1      
317m0023            VIA   -    MD0100PA00X+117941Y+033075X0200Y         S0      
327m0024            PQ4   -D          A01X+111238Y+035544X3327Y4173     S1      
327m0024            PR315 -2A         A01X+117079Y+030794X1260Y2700     S1      
327m0024            PQ5   -D          A01X+111238Y+030794X3327Y4173     S1      
327m0024            PQ6   -D          A01X+111238Y+026044X3327Y4173     S1      
317m0024            VIA   -    MD0100PA00X+113520Y+025486X0200Y         S0      
317m0024            VIA   -    MD0100PA00X+113520Y+025786X0200Y         S0      
317m0024            VIA   -    MD0100PA00X+113820Y+025486X0200Y         S0      
317m0024            VIA   -    MD0100PA00X+113820Y+025786X0200Y         S0      
317m0024            VIA   -    M      A01X+113520Y+026686X0200Y         S2      
017m0024            VIA   -    M      A10X+113520Y+026686X0260Y         S2      
017m0024                  -    MD0100PA00X+113520Y+026686                       
317m0024            VIA   -    MD0100PA00X+113520Y+026386X0200Y         S0      
317m0024            VIA   -    MD0100PA00X+113520Y+026086X0200Y         S0      
317m0024            VIA   -    MD0100PA00X+113820Y+026386X0200Y         S0      
317m0024            VIA   -    MD0100PA00X+113820Y+026086X0200Y         S0      
317m0024            VIA   -    MD0100PA00X+113820Y+026686X0200Y         S0      
317m0024            VIA   -    MD0100PA00X+113840Y+031436X0200Y         S0      
317m0024            VIA   -    MD0100PA00X+113840Y+030836X0200Y         S0      
317m0024            VIA   -    MD0100PA00X+113840Y+031136X0200Y         S0      
317m0024            VIA   -    MD0100PA00X+112155Y+033147X0200Y         S0      
317m0024            VIA   -    MD0100PA00X+113540Y+030836X0200Y         S0      
317m0024            VIA   -    MD0100PA00X+113540Y+031136X0200Y         S0      
317m0024            VIA   -    M      A01X+113540Y+031436X0200Y         S2      
017m0024            VIA   -    M      A10X+113540Y+031436X0260Y         S2      
017m0024                  -    MD0100PA00X+113540Y+031436                       
317m0024            VIA   -    MD0100PA00X+113840Y+030536X0200Y         S0      
317m0024            VIA   -    MD0100PA00X+113840Y+030236X0200Y         S0      
317m0024            VIA   -    MD0100PA00X+112166Y+028459X0200Y         S0      
317m0024            VIA   -    MD0100PA00X+113540Y+030536X0200Y         S0      
317m0024            VIA   -    MD0100PA00X+113540Y+030236X0200Y         S0      
317m0024            VIA   -    MD0100PA00X+110468Y+033179X0200Y         S0      
317m0024            VIA   -    MD0100PA00X+110991Y+033168X0200Y         S0      
317m0024            VIA   -    MD0100PA00X+111280Y+033157X0200Y         S0      
317m0024            VIA   -    MD0100PA00X+111867Y+033157X0200Y         S0      
317m0024            VIA   -    MD0100PA00X+110180Y+033189X0200Y         S0      
317m0024            VIA   -    MD0100PA00X+110479Y+028491X0200Y         S0      
317m0024            VIA   -    MD0100PA00X+111002Y+028481X0200Y         S0      
317m0024            VIA   -    MD0100PA00X+111290Y+028470X0200Y         S0      
317m0024            VIA   -    MD0100PA00X+111877Y+028470X0200Y         S0      
317m0024            VIA   -    MD0100PA00X+110190Y+028502X0200Y         S0      
317m0024            VIA   -    MD0100PA00X+115671Y+031504X0200Y    R180 S0      
317m0024            VIA   -    MD0100PA00X+115971Y+031504X0200Y    R180 S0      
317m0024            VIA   -    MD0100PA00X+116271Y+031504X0200Y    R180 S0      
317m0024            VIA   -    MD0100PA00X+115671Y+031804X0200Y    R180 S0      
317m0024            VIA   -    MD0100PA00X+115971Y+031804X0200Y    R180 S0      
317m0024            VIA   -    MD0100PA00X+116271Y+031804X0200Y    R180 S0      
317m0024            VIA   -    MD0100PA00X+115671Y+032104X0200Y    R180 S0      
317m0024            VIA   -    MD0100PA00X+115971Y+032104X0200Y    R180 S0      
317m0024            VIA   -    MD0100PA00X+116271Y+032104X0200Y    R180 S0      
317m0024            VIA   -    MD0100PA00X+115671Y+030904X0200Y    R180 S0      
317m0024            VIA   -    MD0100PA00X+115971Y+030904X0200Y    R180 S0      
317m0024            VIA   -    MD0100PA00X+116271Y+030904X0200Y    R180 S0      
317m0024            VIA   -    MD0100PA00X+115671Y+031204X0200Y    R180 S0      
317m0024            VIA   -    MD0100PA00X+115971Y+031204X0200Y    R180 S0      
317m0024            VIA   -    MD0100PA00X+116271Y+031204X0200Y    R180 S0      
317m0024            VIA   -    MD0100PA00X+116271Y+029404X0200Y    R180 S0      
317m0024            VIA   -    MD0100PA00X+115971Y+029404X0200Y    R180 S0      
317m0024            VIA   -    MD0100PA00X+115671Y+029404X0200Y    R180 S0      
317m0024            VIA   -    MD0100PA00X+115671Y+029704X0200Y    R180 S0      
317m0024            VIA   -    MD0100PA00X+115971Y+029704X0200Y    R180 S0      
317m0024            VIA   -    MD0100PA00X+116271Y+029704X0200Y    R180 S0      
317m0024            VIA   -    MD0100PA00X+115671Y+030004X0200Y    R180 S0      
317m0024            VIA   -    MD0100PA00X+115971Y+030004X0200Y    R180 S0      
317m0024            VIA   -    MD0100PA00X+116271Y+030004X0200Y    R180 S0      
317m0024            VIA   -    MD0100PA00X+115671Y+030304X0200Y    R180 S0      
317m0024            VIA   -    MD0100PA00X+115971Y+030304X0200Y    R180 S0      
317m0024            VIA   -    MD0100PA00X+116271Y+030304X0200Y    R180 S0      
317m0024            VIA   -    MD0100PA00X+115671Y+030604X0200Y    R180 S0      
317m0024            VIA   -    MD0100PA00X+115971Y+030604X0200Y    R180 S0      
317m0024            VIA   -    MD0100PA00X+116271Y+030604X0200Y    R180 S0      
317m0024            VIA   -    MD0100PA00X+113540Y+034998X0200Y         S0      
317m0024            VIA   -    MD0100PA00X+113840Y+034998X0200Y         S0      
317m0024            VIA   -    MD0100PA00X+113540Y+035298X0200Y         S0      
317m0024            VIA   -    MD0100PA00X+113840Y+035298X0200Y         S0      
317m0024            VIA   -    MD0100PA00X+113540Y+035598X0200Y         S0      
317m0024            VIA   -    MD0100PA00X+113840Y+035598X0200Y         S0      
317m0024            VIA   -    MD0100PA00X+113540Y+035898X0200Y         S0      
317m0024            VIA   -    MD0100PA00X+113840Y+035898X0200Y         S0      
317m0024            VIA   -    M      A01X+113540Y+036198X0200Y         S2      
017m0024            VIA   -    M      A10X+113540Y+036198X0260Y         S2      
017m0024                  -    MD0100PA00X+113540Y+036198                       
317m0024            VIA   -    MD0100PA00X+113840Y+036198X0200Y         S0      
327m0025            PR1   -2A         A01X+117088Y+045044X1260Y2700     S1      
327m0025            PQ1   -D          A01X+111238Y+049794X3327Y4173     S1      
327m0025            PQ2   -D          A01X+111238Y+045044X3327Y4173     S1      
327m0025            PQ3   -D          A01X+111238Y+040294X3327Y4173     S1      
317m0025            VIA   -    MD0100PA00X+113862Y+046773X0200Y         S0      
317m0025            VIA   -    MD0100PA00X+113862Y+048573X0200Y         S0      
317m0025            VIA   -    MD0100PA00X+113862Y+047073X0200Y         S0      
317m0025            VIA   -    MD0100PA00X+113862Y+047973X0200Y         S0      
317m0025            VIA   -    MD0100PA00X+113862Y+047673X0200Y         S0      
317m0025            VIA   -    MD0100PA00X+113862Y+047373X0200Y         S0      
317m0025            VIA   -    MD0100PA00X+113862Y+048273X0200Y         S0      
317m0025            VIA   -    MD0100PA00X+112355Y+047391X0200Y         S0      
317m0025            VIA   -    MD0100PA00X+113562Y+048273X0200Y         S0      
317m0025            VIA   -    MD0100PA00X+113562Y+047373X0200Y         S0      
317m0025            VIA   -    MD0100PA00X+113562Y+047673X0200Y         S0      
317m0025            VIA   -    MD0100PA00X+113562Y+047973X0200Y         S0      
317m0025            VIA   -    M      A01X+113562Y+046773X0200Y         S2      
017m0025            VIA   -    M      A10X+113562Y+046773X0260Y         S2      
017m0025                  -    MD0100PA00X+113562Y+046773                       
317m0025            VIA   -    MD0100PA00X+113562Y+047073X0200Y         S0      
317m0025            VIA   -    MD0100PA00X+113562Y+048573X0200Y         S0      
317m0025            VIA   -    MD0100PA00X+112067Y+047402X0200Y         S0      
317m0025            VIA   -    MD0100PA00X+111480Y+047402X0200Y         S0      
317m0025            VIA   -    MD0100PA00X+111192Y+047413X0200Y         S0      
317m0025            VIA   -    MD0100PA00X+110668Y+047423X0200Y         S0      
317m0025            VIA   -    MD0100PA00X+110380Y+047434X0200Y         S0      
317m0025            VIA   -    MD0100PA00X+115680Y+045754X0200Y    R180 S0      
317m0025            VIA   -    MD0100PA00X+115980Y+045754X0200Y    R180 S0      
317m0025            VIA   -    MD0100PA00X+116280Y+045754X0200Y    R180 S0      
317m0025            VIA   -    MD0100PA00X+115680Y+046054X0200Y    R180 S0      
317m0025            VIA   -    MD0100PA00X+115980Y+046054X0200Y    R180 S0      
317m0025            VIA   -    MD0100PA00X+116280Y+046054X0200Y    R180 S0      
317m0025            VIA   -    MD0100PA00X+115680Y+046354X0200Y    R180 S0      
317m0025            VIA   -    MD0100PA00X+115980Y+046354X0200Y    R180 S0      
317m0025            VIA   -    MD0100PA00X+116280Y+046354X0200Y    R180 S0      
317m0025            VIA   -    MD0100PA00X+113840Y+045723X0200Y         S0      
317m0025            VIA   -    MD0100PA00X+113840Y+044823X0200Y         S0      
317m0025            VIA   -    MD0100PA00X+113840Y+044523X0200Y         S0      
317m0025            VIA   -    MD0100PA00X+113840Y+045123X0200Y         S0      
317m0025            VIA   -    MD0100PA00X+113840Y+045423X0200Y         S0      
317m0025            VIA   -    MD0100PA00X+113540Y+044823X0200Y         S0      
317m0025            VIA   -    MD0100PA00X+113540Y+044523X0200Y         S0      
317m0025            VIA   -    MD0100PA00X+113540Y+045123X0200Y         S0      
317m0025            VIA   -    MD0100PA00X+113540Y+045423X0200Y         S0      
317m0025            VIA   -    M      A01X+113540Y+045723X0200Y         S2      
017m0025            VIA   -    M      A10X+113540Y+045723X0260Y         S2      
017m0025                  -    MD0100PA00X+113540Y+045723                       
317m0025            VIA   -    MD0100PA00X+115680Y+045154X0200Y    R180 S0      
317m0025            VIA   -    MD0100PA00X+115980Y+045154X0200Y    R180 S0      
317m0025            VIA   -    MD0100PA00X+116280Y+045154X0200Y    R180 S0      
317m0025            VIA   -    MD0100PA00X+115680Y+045454X0200Y    R180 S0      
317m0025            VIA   -    MD0100PA00X+115980Y+045454X0200Y    R180 S0      
317m0025            VIA   -    MD0100PA00X+116280Y+045454X0200Y    R180 S0      
317m0025            VIA   -    MD0100PA00X+116280Y+043654X0200Y    R180 S0      
317m0025            VIA   -    MD0100PA00X+115980Y+043654X0200Y    R180 S0      
317m0025            VIA   -    MD0100PA00X+115680Y+043654X0200Y    R180 S0      
317m0025            VIA   -    MD0100PA00X+115680Y+043954X0200Y    R180 S0      
317m0025            VIA   -    MD0100PA00X+115980Y+043954X0200Y    R180 S0      
317m0025            VIA   -    MD0100PA00X+116280Y+043954X0200Y    R180 S0      
317m0025            VIA   -    MD0100PA00X+115680Y+044254X0200Y    R180 S0      
317m0025            VIA   -    MD0100PA00X+115980Y+044254X0200Y    R180 S0      
317m0025            VIA   -    MD0100PA00X+116280Y+044254X0200Y    R180 S0      
317m0025            VIA   -    MD0100PA00X+115680Y+044554X0200Y    R180 S0      
317m0025            VIA   -    MD0100PA00X+115980Y+044554X0200Y    R180 S0      
317m0025            VIA   -    MD0100PA00X+116280Y+044554X0200Y    R180 S0      
317m0025            VIA   -    MD0100PA00X+115680Y+044854X0200Y    R180 S0      
317m0025            VIA   -    MD0100PA00X+115980Y+044854X0200Y    R180 S0      
317m0025            VIA   -    MD0100PA00X+116280Y+044854X0200Y    R180 S0      
317m0025            VIA   -    MD0100PA00X+113819Y+040896X0200Y         S0      
317m0025            VIA   -    MD0100PA00X+113819Y+040596X0200Y         S0      
317m0025            VIA   -    MD0100PA00X+113819Y+040296X0200Y         S0      
317m0025            VIA   -    MD0100PA00X+112376Y+042682X0200Y         S0      
317m0025            VIA   -    M      A01X+113519Y+040896X0200Y         S2      
017m0025            VIA   -    M      A10X+113519Y+040896X0260Y         S2      
017m0025                  -    MD0100PA00X+113519Y+040896                       
317m0025            VIA   -    MD0100PA00X+113519Y+040596X0200Y         S0      
317m0025            VIA   -    MD0100PA00X+113519Y+040296X0200Y         S0      
317m0025            VIA   -    MD0100PA00X+110689Y+042714X0200Y         S0      
317m0025            VIA   -    MD0100PA00X+111212Y+042703X0200Y         S0      
317m0025            VIA   -    MD0100PA00X+111501Y+042692X0200Y         S0      
317m0025            VIA   -    MD0100PA00X+112088Y+042692X0200Y         S0      
317m0025            VIA   -    MD0100PA00X+110401Y+042724X0200Y         S0      
317m0025            VIA   -    MD0100PA00X+113819Y+039696X0200Y         S0      
317m0025            VIA   -    MD0100PA00X+113819Y+039996X0200Y         S0      
317m0025            VIA   -    MD0100PA00X+113519Y+039696X0200Y         S0      
317m0025            VIA   -    MD0100PA00X+113519Y+039996X0200Y         S0      
327m0026            PR5864-2   M      A01X+117784Y+034675X0198Y0197R180 S1      
327m0026            PR6954-1          A01X+117431Y+034175X0280Y0320R090 S1      
317m0026            VIA   -    M      A01X+117784Y+034923X0200Y         S2      
017m0026            VIA   -    M      A10X+117784Y+034923X0260Y         S2      
017m0026                  -    MD0100PA00X+117784Y+034923                       
317m0026            VIA   -    MD0100PA00X+101784Y+015428X0200Y         S0      
327m0026            PU1   -8          A01X+102517Y+015391X0110Y0300R270 S1      
327m0027            PR5864-1   M      A01X+118099Y+034675X0198Y0197R180 S1      
327m0027            PR6955-1          A01X+118451Y+034175X0280Y0320R270 S1      
317m0027            VIA   -    MD0100PA00X+118099Y+034923X0200Y         S0      
317m0027            VIA   -    M      A01X+101791Y+015142X0200Y         S2      
017m0027            VIA   -    M      A10X+101791Y+015142X0260Y         S2      
017m0027                  -    MD0100PA00X+101791Y+015142                       
327m0027            PU1   -9          A01X+102507Y+015194X0110Y0280R270 S1      
317m0028            VIA   -    M      A01X+102217Y+016178X0200Y         S2      
017m0028            VIA   -    M      A10X+102217Y+016178X0260Y         S2      
017m0028                  -    MD0100PA00X+102217Y+016178                       
327m0028            PU1   -4          A01X+102517Y+016178X0110Y0300R270 S1      
327m0028            PR6962-1          A01X+117440Y+047825X0280Y0320R090 S1      
317m0028            VIA   -    MD0100PA00X+117950Y+048025X0200Y         S0      
317m0028            VIA   -    MD0100PA00X+117941Y+033775X0200Y         S0      
327m0028            PR6965-2          A01X+117431Y+033575X0280Y0320R270 S1      
317m0029            VIA   -    MD0100PA00X+102217Y+015588X0200Y         S0      
327m0029            PU1   -7          A01X+102517Y+015588X0110Y0300R270 S1      
327m0029            PR6963-1          A01X+118460Y+047825X0280Y0320R270 S1      
317m0029            VIA   -    M      A01X+117950Y+047675X0200Y    R180 S2      
017m0029            VIA   -    M      A10X+117950Y+047675X0260Y    R180 S2      
017m0029                  -    MD0100PA00X+117950Y+047675                       
327m0029            PR6964-2          A01X+118451Y+033575X0280Y0320R090 S1      
317m0029            VIA   -    MD0100PA00X+117941Y+033425X0200Y    R180 S0      
317m0030            VIA   -    M      A01X+117792Y+049173X0200Y         S2      
017m0030            VIA   -    M      A10X+117792Y+049173X0260Y         S2      
017m0030                  -    MD0100PA00X+117792Y+049173                       
327m0030            PR6957-1          A01X+117440Y+048425X0280Y0320R090 S1      
327m0030            PR6972-2   M      A01X+117792Y+048925X0198Y0197R180 S1      
327m0030            PU1   -5          A01X+102517Y+015981X0110Y0300R270 S1      
317m0030            VIA   -    MD0100PA00X+101903Y+016033X0200Y         S0      
317m0031            VIA   -    MD0100PA00X+118108Y+049173X0200Y         S0      
327m0031            PR6956-1          A01X+118460Y+048425X0280Y0320R270 S1      
327m0031            PR6972-1   M      A01X+118108Y+048925X0198Y0197R180 S1      
327m0031            PU1   -6          A01X+102517Y+015785X0110Y0300R270 S1      
317m0031            VIA   -    M      A01X+101904Y+015731X0200Y         S2      
017m0031            VIA   -    M      A10X+101904Y+015731X0260Y         S2      
017m0031                  -    MD0100PA00X+101904Y+015731                       
317m0032            VIA   -    M      A01X+101970Y+016660X0200Y         S2      
017m0032            VIA   -    M      A10X+101970Y+016660X0260Y         S2      
017m0032                  -    MD0100PA00X+101970Y+016660                       
327m0032            PU1   -3          A01X+102517Y+016966X0110Y0300R270 S1      
327m0032            PR220 -1          A10X+109100Y+039740X0280Y0320R180 S2      
327m0032            PR26  -2          A10X+109242Y+040150X0180Y0200R180 S2      
327m0032            R5862 -2          A10X+108030Y+040692X0198Y0197R090 S2      
317m0032            VIA   -    MD0100PA00X+108650Y+040350X0200Y         S0      
327m0032            PD15  -1          A10X+108634Y+040714X0320Y0340R090 S2      
327m0032            PC82  -1          A10X+108624Y+039994X0280Y0320R090 S2      
327m0033            PR6970-1          A10X+109558Y+035400X0180Y0200R180 S2      
327m0033            VIA   -    M      A10X+109558Y+035864X0260Y         S2      
327m0033            PC563 -2   M      A10X+109334Y+036404X0280Y0320R180 S2      
327m0033            PD14  -2          A10X+108634Y+036824X0320Y0340R270 S2      
327m0034            R5861 -2          A10X+107727Y+036344X0198Y0197     S2      
327m0034            R5863 -1   M      A10X+107727Y+035944X0198Y0197R180 S2      
327m0034            PR14  -1          A01X+106450Y+035964X0280Y0320     S1      
317m0034            VIA   -    MD0100PA00X+106160Y+035964X0200Y         S0      
327m0034            PR15  -1          A01X+106450Y+032374X0280Y0320R180 S1      
317m0034            VIA   -    M      A01X+106160Y+032374X0200Y         S2      
017m0034            VIA   -    M      A10X+106160Y+032374X0260Y         S2      
017m0034                  -    MD0100PA00X+106160Y+032374                       
327m0034            PR16  -1          A01X+106450Y+027624X0280Y0320R180 S1      
317m0034            VIA   -    M      A01X+106160Y+027624X0200Y         S2      
017m0034            VIA   -    M      A10X+106160Y+027624X0260Y         S2      
017m0034                  -    MD0100PA00X+106160Y+027624                       
327m0035            PR8   -1          A01X+106450Y+051374X0280Y0320R180 S1      
317m0035            VIA   -    M      A01X+106160Y+051374X0200Y         S2      
017m0035            VIA   -    M      A10X+106160Y+051374X0260Y         S2      
017m0035                  -    MD0100PA00X+106160Y+051374                       
317m0035            VIA   -    M      A01X+106160Y+046624X0200Y         S2      
017m0035            VIA   -    M      A10X+106160Y+046624X0260Y         S2      
017m0035                  -    MD0100PA00X+106160Y+046624                       
327m0035            PR12  -1          A01X+106450Y+046624X0280Y0320R180 S1      
327m0035            R5862 -1          A10X+108030Y+041008X0198Y0197R090 S2      
327m0035            PR13  -1          A01X+106450Y+041874X0280Y0320R180 S1      
317m0035            VIA   -    MD0100PA00X+106098Y+041874X0200Y         S0      
327m0035            R5860 -1   M      A10X+107680Y+041008X0198Y0197R090 S2      
327m0036            PR6971-2   M      A10X+109200Y+034400X0280Y0320R180 S2      
327m0036            VIA   -           A10X+109200Y+033880X0260Y         S2      
327m0036            PC565 -1          A10X+108624Y+034394X0280Y0320R090 S2      
327m0037            PU1   -2          A01X+102517Y+017162X0110Y0300R270 S1      
317m0037            VIA   -    M      A01X+102200Y+017120X0200Y         S2      
017m0037            VIA   -    M      A10X+102200Y+017120X0260Y         S2      
017m0037                  -    MD0100PA00X+102200Y+017120                       
327m0037            PR6971-1          A10X+109200Y+034980X0280Y0320R180 S2      
327m0037            PR6970-2          A10X+109242Y+035400X0180Y0200R180 S2      
327m0037            PC564 -1          A10X+108624Y+035244X0280Y0320R090 S2      
327m0037            R5863 -2          A10X+108042Y+035944X0198Y0197R180 S2      
317m0037            VIA   -    MD0100PA00X+108650Y+035600X0200Y         S0      
327m0037            PD14  -1          A10X+108634Y+035964X0320Y0340R090 S2      
327P52V_HS1_TEMP    PR6966-1          A01X+110851Y+023174X0180Y0200R180 S1      
317P52V_HS1_TEMP    VIA   -    M      A01X+110611Y+023174X0200Y         S2      
017P52V_HS1_TEMP    VIA   -    M      A10X+110611Y+023174X0260Y         S2      
017P52V_HS1_TEMP          -    MD0100PA00X+110611Y+023174                       
317P52V_HS1_TEMP    VIA   -    MD0100PA00X+103902Y+018592X0200Y         S0      
327P52V_HS1_TEMP    PC6   -1   M      A01X+104150Y+018592X0198Y0197R090 S1      
327P52V_HS1_TEMP    PU1   -35         A01X+104151Y+017615X0110Y0300     S1      
327P52V_HS1_FB      VIA   -           A01X+103429Y+019799X0300Y         S1      
327P52V_HS1_FB      PR24  -1          A01X+103852Y+019370X0198Y0197     S1      
327P52V_HS1_FB      PR23  -2          A01X+102829Y+019927X0440Y0540R180 S1      
327P52V_HS1_FB      PU1   -38         A01X+103560Y+017615X0110Y0300     S1      
327P52V_HS1_CS      VIA   -    M      A01X+106600Y+017550X0300Y         S1      
327P52V_HS1_CS      PR209 -2   M      A01X+106700Y+018592X0198Y0197R270 S1      
327P52V_HS1_CS      PU1   -26         A01X+105194Y+016572X0110Y0300R270 S1      
327P52V_HS1_CS      U29   -1          A01X+107839Y+017478X0150Y0460R180 S1      
327P52V_HS1_SIO     PR213 -1   M      A10X+106308Y+013050X0198Y0197     S2      
327P52V_HS1_SIO     PR212 -1          A10X+104958Y+012550X0198Y0197     S2      
317P52V_HS1_SIO     VIA   -    MD0100PA00X+107072Y+014650X0200Y         S0      
327P52V_HS1_SIO     U29   -5   M      A01X+107072Y+015075X0150Y0460R180 S1      
327P52V_HS1_SIO     PU1   -24         A01X+105194Y+016178X0110Y0300R270 S1      
317P52V_HS1_SIO     VIA   -    M      A01X+108200Y+014360X0200Y         S2      
017P52V_HS1_SIO     VIA   -    M      A10X+108200Y+014360X0260Y         S2      
017P52V_HS1_SIO           -    MD0100PA00X+108200Y+014360                       
327P52V_HS1_SIO     U29   -2          A01X+107583Y+017478X0150Y0460R180 S1      
327P52V_HS1_FLT     R153  -2          A10X+111400Y+014192X0198Y0197R090 S2      
317P52V_HS1_FLT     VIA   -    MD0100PA00X+111542Y+013892X0200Y         S0      
327P52V_HS1_FLT     R151  -2          A01X+111250Y+013892X0198Y0197R270 S1      
317P52V_HS1_FLT     VIA   -    MD0100PA00X+103954Y+017921X0200Y         S0      
327P52V_HS1_FLT     PU1   -36         A01X+103954Y+017615X0110Y0300     S1      
317P52V_HS1_FLT     VIA   -    M      A01X+083175Y+031825X0300Y    R270 S1      
017P52V_HS1_FLT     VIA   -    M      A10X+083175Y+031825X0200Y    R270 S1      
017P52V_HS1_FLT           -    MD0100PA00X+083175Y+031825                       
317P52V_HS1_FLT     VIA   -    MD0100PA00X+086800Y+027150X0200Y         S0      
327P52V_HS1_FLT     U4    -4          A10X+082760Y+031100X0140Y0590R180 S2      
327m0038            PC553 -1          A10X+108624Y+039250X0280Y0320R090 S2      
327m0038            PR220 -2          A10X+109100Y+039160X0280Y0320R180 S2      
327m0038            VIA   -           A10X+109110Y+038640X0260Y         S2      
327HS1_TMR2         VIA   -           A01X+105022Y+012651X0300Y         S1      
327HS1_TMR2         PR33  -2          A01X+104798Y+013127X0198Y0197R180 S1      
327HS1_TMR2         PR211 -1          A01X+104413Y+013127X0198Y0197R180 S1      
327HS1_TMR2         PC83  -1          A01X+104490Y+012650X0280Y0320R090 S1      
327HS1_TMR1         PC551 -1          A01X+104413Y+013527X0198Y0197R180 S1      
327HS1_TMR1         PR210 -2   M      A01X+104800Y+013542X0198Y0197R270 S1      
327HS1_TMR1         VIA   -    M      A01X+105300Y+013650X0300Y         S1      
327HS1_TMR1         PR33  -1          A01X+105113Y+013127X0198Y0197R180 S1      
327m0039            PU1   -37         A01X+103757Y+017615X0110Y0300     S1      
317m0039            VIA   -    M      A01X+103902Y+018303X0200Y         S2      
017m0039            VIA   -    M      A10X+103902Y+018303X0260Y         S2      
017m0039                  -    MD0100PA00X+103902Y+018303                       
327m0039            R167  -1          A10X+057858Y+045750X0198Y0197     S2      
317m0039            VIA   -    MD0100PA00X+070775Y+035875X0200Y         S0      
327m0040            VIA   -    M      A01X+105400Y+018100X0300Y         S1      
327m0040            R5856 -2          A01X+105350Y+018592X0198Y0197R270 S1      
327m0040            PU1   -29         A01X+105194Y+017162X0110Y0300R270 S1      
327m0041            VIA   -    M      A01X+105950Y+017550X0300Y         S1      
327m0041            R5855 -2          A01X+105800Y+018592X0198Y0197R270 S1      
327m0041            PU1   -28         A01X+105194Y+016966X0110Y0300R270 S1      
327P52V_HS1_CLKIN   PR11  -2          A10X+106058Y+014200X0198Y0197R180 S2      
317P52V_HS1_CLKIN   VIA   -    M      A01X+105750Y+015588X0200Y         S2      
017P52V_HS1_CLKIN   VIA   -    M      A10X+105750Y+015588X0260Y         S2      
017P52V_HS1_CLKIN         -    MD0100PA00X+105750Y+015588                       
327P52V_HS1_CLKIN   PU1   -21         A01X+105194Y+015588X0110Y0300R270 S1      
327P52V_HS1_VDSFB   VIA   -           A01X+102894Y+018213X0300Y         S1      
327P52V_HS1_VDSFB   PR25  -2          A01X+102829Y+018877X0440Y0540R180 S1      
327P52V_HS1_VDSFB   PU1   -39         A01X+102773Y+017625X0110Y0280     S1      
327P52V_HS1_DVCC    VIA   -           A01X+107740Y+014130X0300Y         S1      
317P52V_HS1_DVCC    VIA   -    M      A01X+104394Y+014574X0200Y         S2      
017P52V_HS1_DVCC    VIA   -    M      A10X+104394Y+014574X0260Y         S2      
017P52V_HS1_DVCC          -    MD0100PA00X+104394Y+014574                       
327P52V_HS1_DVCC    PU1   -15         A01X+104348Y+014938X0110Y0300     S1      
327P52V_HS1_DVCC    PC5   -2          A01X+104413Y+014327X0198Y0197     S1      
317P52V_HS1_DVCC    VIA   -    MD0100PA00X+107315Y+013780X0200Y         S0      
317P52V_HS1_DVCC    VIA   -    M      A01X+107315Y+014080X0200Y         S2      
017P52V_HS1_DVCC    VIA   -    M      A10X+107315Y+014080X0260Y         S2      
017P52V_HS1_DVCC          -    MD0100PA00X+107315Y+014080                       
327P52V_HS1_DVCC    PC487 -1          A01X+106855Y+013907X0460Y0620R090 S1      
327P52V_HS1_DVCC    U29   -8          A01X+107839Y+015075X0150Y0460R180 S1      
327P52V_HS1_DVCC    U29   -7   M      A01X+107583Y+015075X0150Y0460R180 S1      
327P52V_HS1_DVCC    U29   -3          A01X+107327Y+017478X0150Y0460R180 S1      
327m0042            PR26  -1          A10X+109558Y+040150X0180Y0200R180 S2      
327m0042            VIA   -    M      A10X+109558Y+040631X0260Y         S2      
327m0042            PD15  -2          A10X+108634Y+041574X0320Y0340R270 S2      
327m0042            PC8   -2   M      A10X+109334Y+041154X0280Y0320R180 S2      
327P52V_HS1_TMR     VIA   -    M      A01X+105350Y+014408X0300Y         S1      
327P52V_HS1_TMR     PU1   -20         A01X+105194Y+015391X0110Y0300R270 S1      
327P52V_HS1_TMR     PC7   -1          A01X+104413Y+013927X0198Y0197R180 S1      
327P52V_HS1_TMR     PR210 -1   M      A01X+104800Y+013858X0198Y0197R270 S1      
327P52V_HS1_SCK     PR28  -1   M      A10X+106308Y+013400X0198Y0197     S2      
327P52V_HS1_SCK     PR27  -2          A10X+104958Y+012900X0198Y0197R180 S2      
317P52V_HS1_SCK     VIA   -    MD0100PA00X+106050Y+016450X0200Y         S0      
327P52V_HS1_SCK     VIA   -    M      A01X+106450Y+016600X0300Y         S1      
327P52V_HS1_SCK     PU1   -25         A01X+105194Y+016375X0110Y0300R270 S1      
327P52V_HS1_SCK     U29   -6          A01X+107327Y+015075X0150Y0460R180 S1      
317m0043            VIA   -    MD0100PA00X+110619Y+022424X0200Y         S0      
327m0043            PR6969-2   M      A01X+110859Y+022424X0180Y0200     S1      
327m0043            PC558 -2          A01X+114064Y+020540X0460Y0620R270 S1      
317m0043            VIA   -    M      A01X+113300Y+019800X0200Y         S2      
017m0043            VIA   -    M      A10X+113300Y+019800X0260Y         S2      
017m0043                  -    MD0100PA00X+113300Y+019800                       
327m0043            PC10  -2   M      A01X+113300Y+019558X0198Y0197R090 S1      
327m0043            PR10  -2   M      A10X+113742Y+019650X0198Y0197     S2      
327m0043            PC2   -2          A10X+113742Y+020050X0198Y0197     S2      
327m0043            PC557 -2          A01X+112200Y+019558X0198Y0197R090 S1      
327m0043            PC1   -2          A01X+111400Y+019558X0198Y0197R090 S1      
327m0043            PC9   -2          A01X+110600Y+019558X0198Y0197R090 S1      
327m0043            PR6931-2          A01X+111800Y+019558X0198Y0197R090 S1      
327m0043            PR9   -2          A01X+111000Y+019558X0198Y0197R090 S1      
327m0043            R5908 -2          A10X+107350Y+018908X0198Y0197R270 S2      
317m0043            VIA   -    MD0100PA00X+107350Y+019150X0200Y         S0      
317m0043            VIA   -    MD0100PA00X+107000Y+019150X0200Y         S0      
327m0043            R159  -2          A10X+107000Y+018908X0198Y0197R270 S2      
327m0043            PR24  -2          A01X+104168Y+019370X0198Y0197     S1      
327m0043            PC12  -2          A10X+108792Y+016400X0198Y0197     S2      
317m0043            VIA   -    MD0100PA00X+108552Y+016400X0200Y         S0      
317m0043            VIA   -    MD0100PA00X+108552Y+017450X0200Y         S0      
327m0043            PR36  -2          A10X+108792Y+017450X0198Y0197     S2      
317m0043            VIA   -    MD0100PA00X+108552Y+017100X0200Y         S0      
327m0043            PC11  -2          A10X+108792Y+017100X0198Y0197     S2      
317m0043            VIA   -    MD0100PA00X+108552Y+016750X0200Y         S0      
327m0043            PR37  -2          A10X+108792Y+016750X0198Y0197     S2      
327m0043            PC561 -2          A01X+109639Y+018360X0198Y0197R180 S1      
327m0043            PR20  -2          A01X+109292Y+017350X0198Y0197R180 S1      
327m0043            PR21  -2          A01X+109642Y+018800X0198Y0197R180 S1      
327m0043            PC562 -2          A01X+109560Y+016850X0280Y0320R090 S1      
317m0043            VIA   -    MD0100PA00X+107950Y+018458X0200Y         S0      
327m0043            R158  -2          A10X+107700Y+018458X0198Y0197R270 S2      
327m0043            R5907 -2          A10X+108250Y+018458X0198Y0197R270 S2      
317m0043            VIA   -    MD0100PA00X+108500Y+018458X0200Y         S0      
327m0043            PU1   -33         A01X+104544Y+017615X0110Y0300     S1      
327m0043            PU1   -34         A01X+104348Y+017615X0110Y0300     S1      
317m0043            VIA   -    MD0100PA00X+106700Y+019150X0200Y         S0      
327m0043            PR209 -1   M      A01X+106700Y+018908X0198Y0197R270 S1      
327m0043            PC6   -2   M      A01X+104150Y+018908X0198Y0197R090 S1      
317m0043            VIA   -           A01X+103902Y+018908X0200Y         S2      
017m0043            VIA   -           A10X+103902Y+018908X0260Y         S2      
017m0043                  -     D0100PA00X+103902Y+018908                       
327m0043            PR6932-2          A01X+113328Y+013846X0198Y0197     S1      
327m0043            PC13  -2          A01X+114458Y+014591X0400Y0500     S1      
327m0043            PU7   -19         A01X+113109Y+015312X0120Y0330     S1      
327m0043            PU7   -PAD1M      A01X+112460Y+016670X1100Y2200     S1      
317m0043            VIA   -    MD0100PA00X+112020Y+015700X0200Y         S0      
317m0043            VIA   -    MD0100PA00X+112900Y+017650X0200Y         S0      
317m0043            VIA   -    MD0100PA00X+112900Y+016650X0200Y         S0      
317m0043            VIA   -    MD0100PA00X+112020Y+016650X0200Y         S0      
317m0043            VIA   -    MD0100PA00X+112020Y+017650X0200Y         S0      
317m0043            VIA   -    MD0100PA00X+112900Y+015700X0200Y         S0      
327m0043            R149  -2   M      A01X+112292Y+013846X0198Y0197R180 S1      
317m0043            VIA   -    M      A01X+112052Y+013846X0200Y         S2      
017m0043            VIA   -    M      A10X+112052Y+013846X0260Y         S2      
017m0043                  -    MD0100PA00X+112052Y+013846                       
317m0043            VIA   -    MD0100PA00X+110450Y+013652X0200Y         S0      
327m0043            PR35  -2   M      A01X+110450Y+013892X0198Y0197R270 S1      
317m0043            VIA   -    MD0100PA00X+105752Y+013860X0200Y    R270 S0      
327m0043            PR11  -1          A10X+105742Y+014200X0198Y0197R180 S2      
317m0043            VIA   -    MD0100PA00X+105752Y+013400X0200Y    R270 S0      
327m0043            PR28  -2          A10X+105992Y+013400X0198Y0197     S2      
327m0043            PU1   -14         A01X+104151Y+014938X0110Y0300     S1      
317m0043            VIA   -    MD0100PA00X+103650Y+016300X0200Y         S0      
317m0043            VIA   -    MD0100PA00X+104800Y+016300X0200Y         S0      
317m0043            VIA   -    MD0100PA00X+103650Y+017200X0200Y         S0      
317m0043            VIA   -    MD0100PA00X+103650Y+015350X0200Y         S0      
317m0043            VIA   -    MD0100PA00X+104800Y+015350X0200Y         S0      
317m0043            VIA   -    MD0100PA00X+104800Y+017200X0200Y         S0      
327m0043            PU1   -40  M      A01X+104200Y+016277X1437Y2126     S1      
327m0043            PC551 -2          A01X+104098Y+013527X0198Y0197R180 S1      
327m0043            PC5   -1          A01X+104098Y+014327X0198Y0197     S1      
327m0043            PC7   -2          A01X+104098Y+013927X0198Y0197R180 S1      
327m0043            PJ1   -1          A01X+114564Y+012491X0280Y0740R090 S1      
317m0043            VIA   -    MD0100PA00X+105752Y+013050X0200Y    R270 S0      
327m0043            PR213 -2          A10X+105992Y+013050X0198Y0197     S2      
327m0043            PR211 -2          A01X+104098Y+013127X0198Y0197R180 S1      
327m0043            PC83  -2          A01X+103910Y+012650X0280Y0320R090 S1      
327m0043            PC3   -2          A01X+102500Y+013120X0460Y0620R090 S1      
327m0044            R5906 -1          A10X+104192Y+015100X0198Y0197R180 S2      
327m0044            PR212 -2          A10X+104642Y+012550X0198Y0197     S2      
327m0044            R5905 -1          A10X+104642Y+013750X0198Y0197R180 S2      
327m0044            VIA   -           A10X+103950Y+013450X0260Y         S2      
327m0044            PC4   -1          A10X+103758Y+013950X0198Y0197     S2      
317m0044            VIA   -    MD0100PA00X+103750Y+014200X0200Y         S0      
327m0044            PU1   -13         A01X+103954Y+014938X0110Y0300     S1      
327m0044            PR214 -2          A10X+104642Y+013360X0198Y0197     S2      
327m0044            PR27  -1          A10X+104642Y+012900X0198Y0197R180 S2      
327P52V_HS1_MODE    PR214 -1          A10X+104958Y+013360X0198Y0197     S2      
317P52V_HS1_MODE    VIA   -    M      A01X+105450Y+014850X0200Y         S2      
017P52V_HS1_MODE    VIA   -    M      A10X+105450Y+014850X0260Y         S2      
017P52V_HS1_MODE          -    MD0100PA00X+105450Y+014850                       
327P52V_HS1_MODE    PU1   -19         A01X+105204Y+015194X0110Y0280R270 S1      
327P3V3_AUX_VCC     PC109 -1          A01X+070168Y+005780X0198Y0197R180 S1      
327P3V3_AUX_VCC     PU5   -13         A01X+070098Y+005301X0098Y0276R180 S1      
327m0045            PC102 -1          A01X+069140Y+004772X0180Y0200R270 S1      
327m0045            VIA   -           A01X+066010Y+003990X0300Y         S1      
327m0045            PC567 -1          A01X+066160Y+004570X0400Y0500R270 S1      
327m0045            PC568 -1          A01X+065370Y+004570X0400Y0500R270 S1      
327m0045            PL1   -2          A01X+064710Y+004520X0280Y0320R270 S1      
327m0045            PC566 -1          A01X+066950Y+004570X0400Y0500R270 S1      
327m0045            PU5   -3          A01X+069744Y+004730X0100Y0520R090 S1      
327m0045            PC101 -1          A01X+067740Y+004570X0400Y0500R270 S1      
327m0045            PC100 -1          A01X+068530Y+004570X0400Y0500R270 S1      
327P3V3_AUX_FB      PC111 -1          A01X+069442Y+002700X0198Y0197     S1      
317P3V3_AUX_FB      VIA   -    M      A01X+069442Y+002950X0200Y         S2      
017P3V3_AUX_FB      VIA   -    M      A10X+069442Y+002950X0260Y         S2      
017P3V3_AUX_FB            -    MD0100PA00X+069442Y+002950                       
327P3V3_AUX_FB      PU5   -6          A01X+069902Y+004159X0098Y0276     S1      
327P3V3_AUX_FB      PR90  -1   M      A01X+069442Y+003200X0198Y0197     S1      
327P3V3_AUX_FB      PR91  -1   M      A01X+069446Y+003670X0198Y0197     S1      
327m0046            PC103 -2          A01X+071000Y+004642X0198Y0197R270 S1      
327m0046            PR314 -2          A01X+071000Y+004208X0198Y0197R090 S1      
327SW_P3V3_AUX_BT   PU5   -10         A01X+070335Y+004730X0100Y0360R090 S1      
327SW_P3V3_AUX_BT   PR314 -1          A01X+071000Y+003892X0198Y0197R090 S1      
327P3V3_AUX_PWRGD   PR87  -2          A01X+070458Y+003200X0198Y0197     S1      
327P3V3_AUX_PWRGD   PU5   -9          A01X+070335Y+004533X0100Y0360R090 S1      
317P3V3_AUX_PWRGD   VIA   -    M      A01X+070700Y+003200X0200Y         S2      
017P3V3_AUX_PWRGD   VIA   -    M      A10X+070700Y+003200X0260Y         S2      
017P3V3_AUX_PWRGD         -    MD0100PA00X+070700Y+003200                       
327SW_P3V3_AUX_PH   VIA   -           A01X+071150Y+006130X0300Y         S1      
327SW_P3V3_AUX_PH   PL2   -1          A01X+071798Y+005100X0848Y1300     S1      
327SW_P3V3_AUX_PH   PC103 -1          A01X+071000Y+004958X0198Y0197R270 S1      
327SW_P3V3_AUX_PH   PU5   -11         A01X+070335Y+004927X0100Y0360R090 S1      
327SW_P3V3_AUX_PH   PU5   -2          A01X+069665Y+004927X0100Y0360R090 S1      
327P3V3_AUX_REF     PU5   -8          A01X+070374Y+004336X0098Y0276R090 S1      
327P3V3_AUX_REF     PC110 -2          A01X+070461Y+003670X0198Y0197     S1      
317P3V3_AUX_REF     VIA   -    M      A01X+070374Y+004100X0200Y         S2      
017P3V3_AUX_REF     VIA   -    M      A10X+070374Y+004100X0260Y         S2      
017P3V3_AUX_REF           -    MD0100PA00X+070374Y+004100                       
327P3V3_AUX_MODE    PR88  -1          A01X+070600Y+005642X0198Y0197R090 S1      
327P3V3_AUX_MODE    PU5   -12         A01X+070374Y+005124X0098Y0276R090 S1      
317P3V3_AUX_MODE    VIA   -    M      A01X+070374Y+005412X0200Y         S2      
017P3V3_AUX_MODE    VIA   -    M      A10X+070374Y+005412X0260Y         S2      
017P3V3_AUX_MODE          -    MD0100PA00X+070374Y+005412                       
327P3V3_AUX_CS      PU5   -4          A01X+069665Y+004533X0100Y0360R090 S1      
327P3V3_AUX_CS      PR89  -1          A01X+069008Y+003650X0198Y0197R180 S1      
317P3V3_AUX_CS      VIA   -    M      A01X+069008Y+003950X0200Y         S2      
017P3V3_AUX_CS      VIA   -    M      A10X+069008Y+003950X0260Y         S2      
017P3V3_AUX_CS            -    MD0100PA00X+069008Y+003950                       
327m0047            U4    -8          A10X+083784Y+031100X0140Y0590R180 S2      
317m0047            VIA   -    M      A01X+083650Y+030250X0300Y         S1      
017m0047            VIA   -    M      A10X+083650Y+030250X0200Y         S1      
017m0047                  -    MD0100PA00X+083650Y+030250                       
317m0047            VIA   -    MD0100PA00X+022142Y+031300X0200Y         S0      
327m0047            R182  -2   M      A10X+022142Y+030950X0198Y0197     S2      
327m0047            C62   -1   M      A10X+022142Y+030500X0198Y0197R180 S2      
327m0047            R179  -1          A10X+022142Y+030050X0198Y0197R180 S2      
327m0048            R82   -2          A01X+064558Y+003300X0180Y0200R180 S1      
317m0048            VIA   -    MD0100PA00X+064800Y+003300X0200Y         S0      
327m0048            R83   -1   M      A01X+069008Y+003250X0198Y0197R180 S1      
327m0048            PU5   -5          A01X+069626Y+004336X0098Y0276R270 S1      
317m0048            VIA   -    MD0100PA00X+069790Y+035250X0200Y         S0      
327m0048            C74   -2          A10X+043202Y+045758X0198Y0197R270 S2      
327m0048            U24   -G   M      A10X+042646Y+045174X0320Y0360R090 S2      
327m0048            R200  -1   M      A10X+042709Y+045750X0198Y0197     S2      
317m0048            VIA   -    MD0100PA00X+086160Y+030460X0200Y         S0      
317m0048            VIA   -    MD0100PA00X+085075Y+025075X0200Y         S0      
317m0048            PU2   -8    D0360PA00X+051516Y+026720X0520Y    R270 S3      
317m0048            VIA   -    MD0100PA00X+051858Y+029550X0200Y         S0      
327m0049            VIA   -    M      A10X+060560Y+044845X0260Y         S2      
327m0049            R200  -2          A10X+042394Y+045750X0198Y0197     S2      
327m0049            R177  -1          A10X+022382Y+045542X0198Y0197R270 S2      
327m0049            C60   -1   M      A10X+022382Y+045058X0198Y0197R090 S2      
327m0049            C56   -1   M      A10X+038130Y+045058X0198Y0197R090 S2      
327m0049            R170  -1          A10X+038130Y+045542X0198Y0197R270 S2      
327m0049            R202  -2   M      A10X+041202Y+045058X0198Y0197R270 S2      
327m0049            R195  -1   M      A10X+069626Y+045542X0198Y0197R270 S2      
327m0049            C70   -1          A10X+069626Y+045058X0198Y0197R090 S2      
327BRICK3_PMBADD    PR325 -1          A10X+023957Y+030042X0198Y0197R270 S2      
317BRICK3_PMBADD    PU4   -13   D0360PA00X+023957Y+026720X0520Y    R270 S3      
327m0050            VIA   -    M      A10X+042159Y+043836X0260Y         S2      
327m0050            R201  -2          A10X+042159Y+043350X0198Y0197R180 S2      
327m0050            R202  -1          A10X+041202Y+044742X0198Y0197R270 S2      
327m0050            U24   -D   M      A10X+041858Y+044800X0320Y0360R090 S2      
327TP_J1_A1         VIA   -           A10X+084208Y+015892X0260Y         S2      
317TP_J1_A1         J1    -A1   D0402PA00X+083256Y+014941X0602Y0602R270 S3      
327m0051            VIA   -    M      A10X+089850Y+028569X0260Y         S2      
327m0051            R96   -2          A10X+089850Y+028108X0198Y0197R270 S2      
327m0051            U27   -D          A10X+089794Y+029500X0320Y0360R270 S2      
317m0052            VIA   -    MD0100PA00X+079840Y+032390X0200Y         S0      
327m0052            R5891 -2          A01X+016604Y+024226X0198Y0197R270 S1      
327m0052            U32   -10         A01X+016607Y+023565X0100Y0320R180 S1      
317m0052            VIA   -    M      A01X+016607Y+023875X0200Y    R270 S2      
017m0052            VIA   -    M      A10X+016607Y+023875X0260Y    R270 S2      
017m0052                  -    MD0100PA00X+016607Y+023875                       
317m0052            VIA   -    MD0100PA00X+016140Y+032320X0200Y         S0      
317m0052            J7    -S16  D0340PA00X+004378Y+031472X0500Y    R270 S3      
327m0052            U4    -11         A10X+084552Y+031100X0140Y0590R180 S2      
317m0052            VIA   -    M      A01X+085300Y+030350X0200Y         S2      
017m0052            VIA   -    M      A10X+085300Y+030350X0260Y         S2      
017m0052                  -    MD0100PA00X+085300Y+030350                       
327P12V_HPDB        R5893 -1          A01X+014184Y+023176X0180Y0200R270 S1      
327P12V_HPDB        C93   -1          A01X+015318Y+021894X0180Y0200R090 S1      
317P12V_HPDB        VIA   -    MD0100PA00X+011160Y+025556X0200Y         S0      
317P12V_HPDB        VIA   -    MD0100PA00X+010860Y+025556X0200Y         S0      
317P12V_HPDB        VIA   -    MD0100PA00X+011160Y+026156X0200Y         S0      
317P12V_HPDB        VIA   -    MD0100PA00X+010860Y+026156X0200Y         S0      
317P12V_HPDB        VIA   -    MD0100PA00X+011160Y+025856X0200Y         S0      
317P12V_HPDB        VIA   -    MD0100PA00X+010860Y+025856X0200Y         S0      
327P12V_HPDB        C92   -1          A10X+014723Y+023256X0400Y0500R090 S2      
327P12V_HPDB        D5    -C          A01X+011813Y+025850X0670Y0990R270 S1      
317P12V_HPDB        J7    -S10  D0340PA00X+004378Y+034472X0500Y    R270 S3      
317P12V_HPDB        J7    -S9   D0340PA00X+004878Y+034972X0500Y    R270 S3      
327P12V_HPDB        VIA   -           A01X+007777Y+031396X0300Y         S1      
317P12V_HPDB        J7    -S13  D0340PA00X+004878Y+032972X0500Y    R270 S3      
327P12V_HPDB        VIA   -           A01X+009981Y+029437X0300Y         S1      
327P12V_HPDB        VIA   -           A01X+010623Y+028795X0300Y         S1      
327P12V_HPDB        VIA   -           A01X+008500Y+030731X0300Y         S1      
327P12V_HPDB        VIA   -           A01X+009211Y+030090X0300Y         S1      
317P12V_HPDB        VIA   -    MD0100PA00X+015063Y+021906X0200Y    R270 S0      
327P12V_HPDB        VIA   -           A01X+014490Y+022450X0300Y         S1      
327P12V_HPDB        U32   -20         A01X+015859Y+021833X0100Y0320R090 S1      
317P12V_HPDB        VIA   -    MD0100PA00X+015503Y+023156X0200Y    R270 S0      
317P12V_HPDB        VIA   -    MD0100PA00X+015233Y+023006X0200Y    R270 S0      
317P12V_HPDB        VIA   -    MD0100PA00X+015233Y+022656X0200Y    R270 S0      
317P12V_HPDB        VIA   -    MD0100PA00X+015233Y+022306X0200Y    R270 S0      
317P12V_HPDB        VIA   -    MD0100PA00X+015503Y+022456X0200Y    R270 S0      
317P12V_HPDB        VIA   -    MD0100PA00X+015503Y+022806X0200Y    R270 S0      
327P12V_HPDB        U32   -13         A01X+015859Y+023211X0100Y0320R090 S1      
327P12V_HPDB        U32   -14         A01X+015859Y+023014X0100Y0320R090 S1      
327P12V_HPDB        U32   -15         A01X+015859Y+022817X0100Y0320R090 S1      
327P12V_HPDB        U32   -16         A01X+015859Y+022620X0100Y0320R090 S1      
327P12V_HPDB        U32   -17         A01X+015859Y+022423X0100Y0320R090 S1      
327P12V_HPDB        U32   -18         A01X+015859Y+022226X0100Y0320R090 S1      
327P12V_HPDB        U32   -19         A01X+015859Y+022029X0100Y0320R090 S1      
327P12V_HPDB        R5896 -1          A01X+015898Y+024914X0180Y0200R180 S1      
327m0053            PR78  -1   M      A10X+024744Y+030042X0180Y0200R090 S2      
327m0053            PR322 -1          A10X+025150Y+030042X0198Y0197R270 S2      
317m0053            PU4   -14   D0360PA00X+024744Y+026720X0520Y    R270 S3      
327m0054            PR319 -1          A10X+068051Y+030042X0198Y0197R270 S2      
317m0054            PU6   -9    D0360PA00X+068051Y+026720X0520Y    R270 S3      
327SMB_BRICK2_SDA   R196  -2          A10X+068856Y+030050X0198Y0197R180 S2      
317SMB_BRICK2_SDA   PU6   -10   D0360PA00X+068839Y+026720X0520Y    R270 S3      
327SMB_BRICK2_SCL   R198  -2          A10X+070656Y+030050X0198Y0197R180 S2      
317SMB_BRICK2_SCL   PU6   -12   D0360PA00X+070414Y+026720X0520Y    R270 S3      
327BRICK2_PMBADD    PR320 -2          A10X+071201Y+030042X0198Y0197R090 S2      
317BRICK2_PMBADD    PU6   -13   D0360PA00X+071201Y+026720X0520Y    R270 S3      
327m0055            R195  -2          A10X+069626Y+045858X0198Y0197R270 S2      
317m0055            PU6   -2    D0630PA00X+069626Y+047720X0930Y    R270 S3      
327m0056            R197  -2          A10X+069756Y+030050X0198Y0197R180 S2      
317m0056            PU6   -11   D0360PA00X+069626Y+026720X0520Y    R270 S3      
327FM_U5_VCC        VIA   -    M      A10X+090582Y+030282X0260Y         S2      
327FM_U5_VCC        U5    -2          A10X+090850Y+030926X0170Y0240     S2      
327FM_U5_VCC        R24   -1          A10X+090450Y+029758X0198Y0197R090 S2      
327PWRGD_GPU_HSC    R28   -2   M      A10X+083442Y+032800X0198Y0197     S2      
327PWRGD_GPU_HSC    R188  -2          A10X+083442Y+032350X0198Y0197     S2      
327PWRGD_GPU_HSC    R185  -1   M      A10X+082708Y+033400X0198Y0197     S2      
327PWRGD_GPU_HSC    R189  -1   M      A10X+083442Y+033250X0198Y0197R180 S2      
327PWRGD_GPU_HSC    VIA   -    M      A10X+006840Y+032370X0260Y         S2      
317PWRGD_GPU_HSC    J7    -S4   D0340PA00X+003878Y+032972X0500Y    R270 S3      
327m0057            VIA   -    M      A10X+081950Y+033650X0260Y         S2      
327m0057            R185  -2          A10X+082392Y+033400X0198Y0197     S2      
327m0057            U6    -2          A10X+082850Y+034226X0170Y0240     S2      
327m0058            C16   -1   M      A10X+087750Y+027792X0198Y0197R270 S2      
327m0058            R30   -2          A10X+082150Y+035808X0198Y0197R270 S2      
327m0058            R189  -2   M      A10X+083758Y+033250X0198Y0197R180 S2      
327m0058            VIA   -    M      A10X+087105Y+026695X0260Y         S2      
317m0058            J1    -C3   D0402PA00X+081256Y+012941X0602Y    R270 S3      
327m0059            VIA   -    M      A10X+075302Y+033850X0260Y         S2      
327m0059            R127  -1          A10X+074808Y+033450X0198Y0197     S2      
327m0059            R184  -1   M      A10X+074808Y+033850X0198Y0197     S2      
327m0059            U25   -13         A10X+076028Y+034160X0160Y0440R090 S2      
327P52V_1_FUSE_1    PD6   -C          A10X+118356Y+015645X0950Y1300R090 S2      
327P52V_1_FUSE_1    R5886 -1          A01X+116600Y+014824X0440Y0540R090 S1      
327P52V_1_FUSE_1    FS1   -1          A01X+118310Y+017609X1280Y1350R090 S1      
327P52V_1_FUSE_1    PD7   -C   M      A01X+118356Y+015645X0950Y1300R270 S1      
317P52V_1_FUSE_1    VIA   -    MD0100PA00X+117752Y+016295X0200Y    R090 S0      
317P52V_1_FUSE_1    VIA   -    M      A01X+117752Y+016595X0200Y    R090 S2      
017P52V_1_FUSE_1    VIA   -    M      A10X+117752Y+016595X0260Y    R090 S2      
017P52V_1_FUSE_1          -    MD0100PA00X+117752Y+016595                       
317P52V_1_FUSE_1    VIA   -    MD0100PA00X+118052Y+016595X0200Y    R090 S0      
317P52V_1_FUSE_1    VIA   -    MD0100PA00X+118052Y+016295X0200Y    R090 S0      
317P52V_1_FUSE_1    VIA   -    MD0100PA00X+118302Y+016295X0200Y    R090 S0      
317P52V_1_FUSE_1    VIA   -    MD0100PA00X+118552Y+016295X0200Y    R090 S0      
317P52V_1_FUSE_1    VIA   -    MD0100PA00X+118862Y+016278X0200Y    R090 S0      
317P52V_1_FUSE_1    VIA   -    M      A01X+118860Y+016600X0200Y    R090 S2      
017P52V_1_FUSE_1    VIA   -    M      A10X+118860Y+016600X0260Y    R090 S2      
017P52V_1_FUSE_1          -    MD0100PA00X+118860Y+016600                       
317P52V_1_FUSE_1    VIA   -    MD0100PA00X+118552Y+016595X0200Y    R090 S0      
317P52V_1_FUSE_1    VIA   -    MD0100PA00X+118302Y+016595X0200Y    R090 S0      
317m0060            VIA   -    M      A01X+092374Y+034550X0300Y         S1      
017m0060            VIA   -    M      A10X+092374Y+034550X0200Y         S1      
017m0060                  -    MD0100PA00X+092374Y+034550                       
327m0060            U20   -D   M      A10X+090894Y+034550X0320Y0360R270 S2      
327m0060            R142  -2          A10X+090950Y+033558X0198Y0197R270 S2      
327m0060            U9    -1          A10X+092374Y+034118X0180Y0520     S2      
327m0060            U8    -1          A10X+085224Y+034018X0180Y0520     S2      
327m0061            R3    -1          A10X+093320Y+035096X0198Y0197R090 S2      
317m0061            VIA   -    M      A01X+093320Y+035336X0300Y         S1      
017m0061            VIA   -    M      A10X+093320Y+035336X0200Y         S1      
017m0061                  -    MD0100PA00X+093320Y+035336                       
317m0061            VIA   -    MD0100PA00X+090350Y+032798X0200Y         S0      
317m0061            J7    -S11  D0340PA00X+004878Y+033972X0500Y    R270 S3      
327m0061            U20   -G          A10X+090106Y+034176X0320Y0360R270 S2      
327m0061            R27   -2          A10X+090350Y+032558X0198Y0197R270 S2      
317m0062            VIA   -    M      A01X+090594Y+032037X0300Y         S1      
017m0062            VIA   -    M      A10X+090594Y+032037X0200Y         S1      
017m0062                  -    MD0100PA00X+090594Y+032037                       
327m0062            R27   -1          A10X+090350Y+032242X0198Y0197R270 S2      
327m0062            U5    -4          A10X+090594Y+031674X0170Y0240     S2      
327m0062            R140  -2   M      A10X+090800Y+032242X0198Y0197R090 S2      
327m0063            VIA   -    M      A10X+091450Y+030391X0260Y         S2      
327m0063            U5    -1          A10X+091106Y+030926X0170Y0240     S2      
327m0063            R187  -2   M      A10X+091450Y+029758X0198Y0197R270 S2      
327m0063            R141  -2          A10X+090950Y+029758X0198Y0197R270 S2      
327m0064            C15   -1          A10X+091550Y+027792X0198Y0197R270 S2      
327m0064            R139  -2   M      A10X+091950Y+027792X0198Y0197R090 S2      
327m0064            VIA   -    M      A10X+091308Y+027150X0260Y         S2      
317m0064            J1    -B2   D0402PA00X+082256Y+013941X0602Y    R270 S3      
327m0065            VIA   -    M      A10X+091514Y+028861X0260Y         S2      
327m0065            R141  -1          A10X+090950Y+029442X0198Y0197R270 S2      
327m0065            R139  -1          A10X+091950Y+028108X0198Y0197R090 S2      
327m0066            R146  -2          A01X+110004Y+015610X0198Y0197     S1      
327m0066            R81   -2   M      A01X+110004Y+016041X0198Y0197     S1      
327m0066            VIA   -    M      A01X+110550Y+016178X0300Y         S1      
327m0066            PU7   -9          A01X+111652Y+016178X0120Y0330R270 S1      
327BOARD_ID_2       VIA   -    M      A10X+084141Y+028057X0260Y         S2      
327BOARD_ID_2       U4    -17         A10X+083784Y+028800X0140Y0590R180 S2      
327BOARD_ID_2       R133  -2   M      A10X+084600Y+027608X0198Y0197R270 S2      
327BOARD_ID_2       R136  -1          A10X+084600Y+026608X0198Y0197R090 S2      
317BOARD_ID_1       VIA   -    M      A01X+085350Y+026858X0300Y         S1      
017BOARD_ID_1       VIA   -    M      A10X+085350Y+026858X0200Y         S1      
017BOARD_ID_1             -    MD0100PA00X+085350Y+026858                       
327BOARD_ID_1       U4    -16         A10X+084040Y+028800X0140Y0590R180 S2      
327BOARD_ID_1       R134  -2   M      A10X+085100Y+027608X0198Y0197R270 S2      
327BOARD_ID_1       R137  -1          A10X+085100Y+026608X0198Y0197R090 S2      
327BOARD_ID_0       VIA   -    M      A10X+084950Y+028150X0260Y         S2      
327BOARD_ID_0       U4    -15         A10X+084296Y+028800X0140Y0590R180 S2      
327BOARD_ID_0       R135  -2   M      A10X+085600Y+027608X0198Y0197R270 S2      
327BOARD_ID_0       R138  -1          A10X+085600Y+026608X0198Y0197R090 S2      
327m0067            VIA   -    M      A10X+082321Y+028121X0260Y         S2      
327m0067            U4    -22         A10X+082504Y+028800X0140Y0590R180 S2      
327m0067            R118  -2          A10X+082100Y+027608X0198Y0197R270 S2      
327m0068            VIA   -    M      A10X+081550Y+028150X0260Y         S2      
327m0068            U4    -23         A10X+082248Y+028800X0140Y0590R180 S2      
327m0068            R117  -2          A10X+081600Y+027608X0198Y0197R270 S2      
327m0069            VIA   -    M      A10X+037848Y+031411X0260Y         S2      
317m0069            VIA   -    MD0100PA00X+073508Y+033600X0200Y         S0      
327m0069            R5878 -1   M      A10X+073508Y+033850X0198Y0197     S2      
327m0069            R184  -2          A10X+074492Y+033850X0198Y0197     S2      
317m0069            VIA   -    MD0100PA00X+069710Y+031340X0200Y         S0      
327m0069            R194  -2   M      A10X+070341Y+031050X0198Y0197     S2      
327m0069            C73   -1   M      A10X+070341Y+030550X0198Y0197R180 S2      
327m0069            R198  -1          A10X+070341Y+030050X0198Y0197R180 S2      
327m0069            R176  -2   M      A10X+037842Y+030950X0198Y0197     S2      
327m0069            C59   -1   M      A10X+037842Y+030500X0198Y0197R180 S2      
327m0069            R173  -1          A10X+037842Y+030050X0198Y0197R180 S2      
327m0069            R183  -2   M      A10X+023042Y+030950X0198Y0197     S2      
327m0069            C63   -1   M      A10X+023042Y+030500X0198Y0197R180 S2      
327m0069            R180  -1          A10X+023042Y+030050X0198Y0197R180 S2      
317m0069            VIA   -    MD0100PA00X+038296Y+031375X0200Y         S0      
317m0069            VIA   -    MD0100PA00X+023042Y+031360X0200Y         S0      
317m0069            VIA   -    MD0100PA00X+053962Y+031340X0200Y         S0      
327m0069            R166  -1          A10X+054592Y+030050X0198Y0197R180 S2      
327m0069            C54   -1   M      A10X+054592Y+030550X0198Y0197R180 S2      
327m0069            R161  -2   M      A10X+054592Y+031050X0198Y0197     S2      
327m0070            VIA   -    M      A10X+076624Y+036645X0260Y         S2      
327m0070            U25   -8   M      A10X+078272Y+034160X0160Y0440R090 S2      
327m0070            R77   -1          A10X+015508Y+035050X0198Y0197     S2      
327m0070            R130  -1          A10X+079742Y+033500X0198Y0197R180 S2      
317m0071            VIA   -    MD0100PA00X+080842Y+034400X0200Y         S0      
327m0071            R125  -1   M      A10X+079742Y+034650X0198Y0197R180 S2      
327m0071            U25   -5          A10X+078272Y+034928X0160Y0440R090 S2      
317m0071            VIA   -    M      A01X+081600Y+027052X0300Y         S1      
017m0071            VIA   -    M      A10X+081600Y+027052X0200Y         S1      
017m0071                  -    MD0100PA00X+081600Y+027052                       
327m0071            R117  -1          A10X+081600Y+027292X0198Y0197R270 S2      
327m0071            R41   -2          A10X+086450Y+035608X0198Y0197R270 S2      
317m0071            VIA   -    MD0100PA00X+086450Y+035850X0200Y         S0      
327m0072            R129  -1          A10X+079742Y+033000X0198Y0197R180 S2      
327m0072            VIA   -    M      A10X+075300Y+036650X0260Y         S2      
327m0072            U25   -9   M      A10X+078272Y+033904X0160Y0440R090 S2      
327m0072            R76   -1          A10X+015508Y+034650X0198Y0197     S2      
317m0073            VIA   -    MD0100PA00X+080842Y+033400X0200Y         S0      
327m0073            R126  -1   M      A10X+080842Y+034100X0198Y0197R180 S2      
327m0073            U25   -6          A10X+078272Y+034672X0160Y0440R090 S2      
317m0073            VIA   -    MD0100PA00X+082100Y+027052X0200Y         S0      
327m0073            R118  -1          A10X+082100Y+027292X0198Y0197R270 S2      
327m0073            R42   -2          A10X+086900Y+035608X0198Y0197R270 S2      
317m0073            VIA   -    M      A01X+086900Y+036050X0200Y         S2      
017m0073            VIA   -    M      A10X+086900Y+036050X0260Y         S2      
017m0073                  -    MD0100PA00X+086900Y+036050                       
327m0074            R131  -1   M      A10X+074808Y+035320X0198Y0197     S2      
327m0074            U25   -16         A10X+076028Y+034928X0160Y0440R090 S2      
327m0074            VIA   -    M      A10X+016325Y+033550X0260Y         S2      
327m0074            R78   -1          A10X+015508Y+033550X0198Y0197     S2      
327m0075            U25   -15         A10X+076028Y+034672X0160Y0440R090 S2      
327m0075            R132  -1   M      A10X+074808Y+034770X0198Y0197     S2      
327m0075            VIA   -    M      A10X+017130Y+033347X0260Y         S2      
327m0075            R79   -1          A10X+015508Y+033100X0198Y0197     S2      
317LED_D3_R         VIA   -    M      A01X+080600Y+026508X0200Y         S2      
017LED_D3_R         VIA   -    M      A10X+080600Y+026508X0260Y         S2      
017LED_D3_R               -    MD0100PA00X+080600Y+026508                       
327LED_D3_R         R59   -2          A01X+080350Y+026508X0198Y0197R090 S1      
327LED_D3_R         D3    -A          A01X+080950Y+026587X0240Y0280R270 S1      
327PU_9543_0_INT1   VIA   -    M      A10X+079156Y+034292X0260Y         S2      
327PU_9543_0_INT1   U25   -7          A10X+078272Y+034416X0160Y0440R090 S2      
327PU_9543_0_INT1   R101  -1          A10X+079742Y+034100X0198Y0197R180 S2      
317m0076            VIA   -    MD0100PA00X+073508Y+032600X0200Y         S0      
327m0076            R128  -1          A10X+074808Y+032850X0198Y0197     S2      
327m0076            U25   -12         A10X+076028Y+033904X0160Y0440R090 S2      
327m0076            R5879 -1   M      A10X+073508Y+032850X0198Y0197     S2      
327m0076            R192  -2   M      A10X+068541Y+031050X0198Y0197     S2      
317m0076            VIA   -    M      A01X+068040Y+031050X0200Y         S2      
017m0076            VIA   -    M      A10X+068040Y+031050X0260Y         S2      
017m0076                  -    MD0100PA00X+068040Y+031050                       
327m0076            R196  -1          A10X+068541Y+030050X0198Y0197R180 S2      
327m0076            C71   -1   M      A10X+068541Y+030550X0198Y0197R180 S2      
327m0076            R174  -2   M      A10X+038742Y+030950X0198Y0197     S2      
327m0076            C57   -1   M      A10X+038742Y+030500X0198Y0197R180 S2      
327m0076            R171  -1          A10X+038742Y+030050X0198Y0197R180 S2      
327m0076            R181  -2   M      A10X+021292Y+030950X0198Y0197     S2      
327m0076            C61   -1   M      A10X+021292Y+030500X0198Y0197R180 S2      
327m0076            R178  -1          A10X+021292Y+030050X0198Y0197R180 S2      
317m0076            VIA   -    MD0100PA00X+038296Y+031640X0200Y         S0      
317m0076            VIA   -    MD0100PA00X+021292Y+031550X0200Y         S0      
317m0076            VIA   -    MD0100PA00X+053962Y+031640X0200Y         S0      
327m0076            R164  -1          A10X+052792Y+030050X0198Y0197R180 S2      
327m0076            C52   -1   M      A10X+052792Y+030550X0198Y0197R180 S2      
327m0076            R163  -2   M      A10X+052792Y+031050X0198Y0197     S2      
317m0077            VIA   -    M      A01X+119341Y+032875X0200Y         S2      
017m0077            VIA   -    M      A10X+119341Y+032875X0260Y         S2      
017m0077                  -    MD0100PA00X+119341Y+032875                       
327m0077            PR6961-2   M      A01X+119031Y+032875X0280Y0320R270 S1      
327m0077            PR6955-2          A01X+119031Y+034175X0280Y0320R270 S1      
327m0077            PR6964-1   M      A01X+119031Y+033575X0280Y0320R090 S1      
327m0077            PR315 -1B         A01X+118271Y+030794X0100Y0200R180 S1      
317m0077            VIA   -    MD0100PA00X+117965Y+030594X0200Y         S0      
317m0078            VIA   -    M      A01X+116507Y+032875X0200Y         S2      
017m0078            VIA   -    M      A10X+116507Y+032875X0260Y         S2      
017m0078                  -    MD0100PA00X+116507Y+032875                       
327m0078            PR6959-2   M      A01X+116851Y+032875X0280Y0320R090 S1      
327m0078            PR6954-2          A01X+116851Y+034175X0280Y0320R090 S1      
327m0078            PR6965-1   M      A01X+116851Y+033575X0280Y0320R270 S1      
327m0078            PR315 -2B         A01X+117659Y+030794X0100Y0200R180 S1      
317m0078            VIA   -    MD0100PA00X+117965Y+030994X0200Y         S0      
327m0079            VIA   -    M      A10X+077542Y+036450X0260Y         S2      
327m0079            U25   -3          A10X+078272Y+035440X0160Y0440R090 S2      
327m0079            R113  -2          A10X+077542Y+036950X0198Y0197     S2      
327TP_J5_D1         VIA   -           A10X+127150Y+028200X0260Y         S2      
317TP_J5_D1         J5    -D1   D0402PA00X+125602Y+028693X0602Y         S3      
327TP_J5_C1         VIA   -           A10X+127000Y+029000X0260Y         S2      
317TP_J5_C1         J5    -C1   D0402PA00X+124602Y+028693X0602Y         S3      
327NC_U1_READY      VIA   -           A10X+094550Y+031900X0260Y         S2      
327NC_U1_READY      U1    -5          A10X+094104Y+032260X0140Y0560R180 S2      
327NC_U6            VIA   -           A10X+083350Y+033700X0260Y         S2      
327NC_U6            U6    -1          A10X+083106Y+034226X0170Y0240     S2      
327m0080            VIA   -    M      A10X+079100Y+036200X0260Y         S2      
327m0080            U25   -1          A10X+078272Y+035952X0160Y0440R090 S2      
327m0080            R98   -2   M      A10X+079742Y+036200X0198Y0197     S2      
327m0080            R97   -1          A10X+080842Y+036200X0198Y0197R180 S2      
317m0081            VIA   -    M      A01X+079200Y+035800X0300Y         S1      
017m0081            VIA   -    M      A10X+079200Y+035800X0200Y         S1      
017m0081                  -    MD0100PA00X+079200Y+035800                       
327m0081            U25   -2          A10X+078272Y+035696X0160Y0440R090 S2      
327m0081            R103  -1          A10X+080842Y+035700X0198Y0197R180 S2      
327m0081            R102  -2   M      A10X+079742Y+035700X0198Y0197     S2      
327m0082            VIA   -           A10X+075900Y+036550X0260Y         S2      
327m0082            U25   -17         A10X+076028Y+035184X0160Y0440R090 S2      
327PU_9543_1_INT1   VIA   -    M      A10X+075355Y+034416X0260Y         S2      
327PU_9543_1_INT1   R106  -1          A10X+074808Y+034250X0198Y0197     S2      
327PU_9543_1_INT1   U25   -14         A10X+076028Y+034416X0160Y0440R090 S2      
327PU_9543_1_INT0   VIA   -    M      A10X+075350Y+032600X0260Y         S2      
327PU_9543_1_INT0   R105  -1          A10X+074808Y+032450X0198Y0197     S2      
327PU_9543_1_INT0   U25   -11         A10X+076028Y+033648X0160Y0440R090 S2      
327PU_9543_0_INT0   VIA   -    M      A10X+079073Y+035184X0260Y         S2      
327PU_9543_0_INT0   U25   -4          A10X+078272Y+035184X0160Y0440R090 S2      
327PU_9543_0_INT0   R100  -1          A10X+079742Y+035200X0198Y0197R180 S2      
327m0083            VIA   -    M      A10X+089068Y+027262X0260Y         S2      
317m0083            J1    -D3   D0402PA00X+081256Y+011941X0602Y    R270 S3      
327m0083            R96   -1   M      A10X+089850Y+027792X0198Y0197R270 S2      
327m0083            C47   -1          A10X+089450Y+027792X0198Y0197R270 S2      
317P52V_HS_FILTER   PC113 -1   MD0420PA00X+073398Y+053900X0620Y0620     S3      
317P52V_HS_FILTER   PC115 -1   MD0420PA00X+063798Y+053900X0620Y0620     S3      
317P52V_HS_FILTER   VIA   -    MD0100PA00X+073738Y+049800X0200Y    R180 S0      
317P52V_HS_FILTER   VIA   -    M      A01X+074038Y+049800X0200Y    R180 S2      
017P52V_HS_FILTER   VIA   -    M      A10X+074038Y+049800X0260Y    R180 S2      
017P52V_HS_FILTER         -    MD0100PA00X+074038Y+049800                       
317P52V_HS_FILTER   VIA   -    MD0100PA00X+073738Y+051800X0200Y         S0      
317P52V_HS_FILTER   VIA   -    M      A01X+074038Y+051800X0200Y         S2      
017P52V_HS_FILTER   VIA   -    M      A10X+074038Y+051800X0260Y         S2      
017P52V_HS_FILTER         -    MD0100PA00X+074038Y+051800                       
317P52V_HS_FILTER   VIA   -    MD0100PA00X+068938Y+049800X0200Y    R180 S0      
317P52V_HS_FILTER   VIA   -    M      A01X+069238Y+049800X0200Y    R180 S2      
017P52V_HS_FILTER   VIA   -    M      A10X+069238Y+049800X0260Y    R180 S2      
017P52V_HS_FILTER         -    MD0100PA00X+069238Y+049800                       
317P52V_HS_FILTER   VIA   -    MD0100PA00X+068938Y+051800X0200Y         S0      
317P52V_HS_FILTER   VIA   -    M      A01X+069238Y+051800X0200Y         S2      
017P52V_HS_FILTER   VIA   -    M      A10X+069238Y+051800X0260Y         S2      
017P52V_HS_FILTER         -    MD0100PA00X+069238Y+051800                       
317P52V_HS_FILTER   VIA   -    MD0100PA00X+064138Y+049800X0200Y    R180 S0      
317P52V_HS_FILTER   VIA   -    M      A01X+064438Y+049800X0200Y    R180 S2      
017P52V_HS_FILTER   VIA   -    M      A10X+064438Y+049800X0260Y    R180 S2      
017P52V_HS_FILTER         -    MD0100PA00X+064438Y+049800                       
317P52V_HS_FILTER   VIA   -    MD0100PA00X+064138Y+051800X0200Y         S0      
317P52V_HS_FILTER   VIA   -    M      A01X+064438Y+051800X0200Y         S2      
017P52V_HS_FILTER   VIA   -    M      A10X+064438Y+051800X0260Y         S2      
017P52V_HS_FILTER         -    MD0100PA00X+064438Y+051800                       
327P52V_HS_FILTER   L3    -2          A01X+086162Y+051307X1160Y1970R180 S1      
327P52V_HS_FILTER   PC119 -1          A01X+073868Y+050350X0460Y0620R180 S1      
327P52V_HS_FILTER   PC116 -1          A01X+073868Y+051250X0460Y0620R180 S1      
327P52V_HS_FILTER   PC118 -1          A01X+069068Y+050350X0460Y0620R180 S1      
327P52V_HS_FILTER   PC117 -1          A01X+069068Y+051250X0460Y0620R180 S1      
327P52V_HS_FILTER   PC121 -1          A01X+064268Y+050350X0460Y0620R180 S1      
327P52V_HS_FILTER   PC120 -1          A01X+064268Y+051250X0460Y0620R180 S1      
327P52V_HS_FILTER   PC19  -1          A01X+058120Y+050350X0460Y0620R180 S1      
327P52V_HS_FILTER   PC18  -1          A01X+058120Y+051250X0460Y0620R180 S1      
327P52V_HS_FILTER   PC21  -1          A01X+053320Y+051250X0460Y0620R180 S1      
327P52V_HS_FILTER   PC20  -1          A01X+053320Y+050350X0460Y0620R180 S1      
327P52V_HS_FILTER   PC23  -1          A01X+048520Y+050350X0460Y0620R180 S1      
327P52V_HS_FILTER   PC22  -1          A01X+048520Y+051250X0460Y0620R180 S1      
327P52V_HS_FILTER   PC47  -1          A01X+042372Y+051250X0460Y0620R180 S1      
327P52V_HS_FILTER   PC46  -1          A01X+042372Y+050350X0460Y0620R180 S1      
327P52V_HS_FILTER   PC49  -1          A01X+037572Y+050350X0460Y0620R180 S1      
327P52V_HS_FILTER   PC48  -1          A01X+037572Y+051250X0460Y0620R180 S1      
327P52V_HS_FILTER   PC51  -1          A01X+032772Y+051250X0460Y0620R180 S1      
327P52V_HS_FILTER   PC50  -1          A01X+032772Y+050350X0460Y0620R180 S1      
327P52V_HS_FILTER   PC79  -1          A01X+026624Y+051250X0460Y0620R180 S1      
327P52V_HS_FILTER   PC78  -1          A01X+026624Y+050350X0460Y0620R180 S1      
327P52V_HS_FILTER   PC77  -1          A01X+021824Y+050350X0460Y0620R180 S1      
327P52V_HS_FILTER   PC76  -1          A01X+021824Y+051250X0460Y0620R180 S1      
327P52V_HS_FILTER   PC75  -1          A01X+017024Y+051250X0460Y0620R180 S1      
327P52V_HS_FILTER   PC74  -1          A01X+017024Y+050350X0460Y0620R180 S1      
327P52V_HS_FILTER   L1    -2          A01X+086392Y+046714X1160Y1970R090 S1      
327P52V_HS_FILTER   L5    -2          A01X+080732Y+046714X1160Y1970R090 S1      
317P52V_HS_FILTER   PC72  -1   MD0420PA00X+021354Y+053900X0620Y0620     S3      
317P52V_HS_FILTER   PC73  -1   MD0420PA00X+016554Y+053900X0620Y0620     S3      
317P52V_HS_FILTER   VIA   -    MD0100PA00X+087426Y+048350X0200Y         S0      
317P52V_HS_FILTER   VIA   -    MD0100PA00X+087126Y+047768X0200Y         S0      
317P52V_HS_FILTER   VIA   -    MD0100PA00X+087126Y+048050X0200Y         S0      
317P52V_HS_FILTER   VIA   -    MD0100PA00X+087126Y+047468X0200Y         S0      
317P52V_HS_FILTER   VIA   -    MD0100PA00X+087126Y+048350X0200Y         S0      
317P52V_HS_FILTER   VIA   -    MD0100PA00X+087426Y+047468X0200Y         S0      
317P52V_HS_FILTER   VIA   -    MD0100PA00X+087426Y+048050X0200Y         S0      
317P52V_HS_FILTER   VIA   -    MD0100PA00X+087426Y+047768X0200Y         S0      
317P52V_HS_FILTER   VIA   -    MD0100PA00X+087431Y+048633X0200Y         S0      
317P52V_HS_FILTER   VIA   -    MD0100PA00X+087131Y+048633X0200Y         S0      
317P52V_HS_FILTER   VIA   -    MD0100PA00X+086526Y+047768X0200Y         S0      
317P52V_HS_FILTER   VIA   -    MD0100PA00X+086526Y+048050X0200Y         S0      
317P52V_HS_FILTER   VIA   -    MD0100PA00X+086526Y+047468X0200Y         S0      
317P52V_HS_FILTER   VIA   -    MD0100PA00X+086826Y+047468X0200Y         S0      
317P52V_HS_FILTER   VIA   -    MD0100PA00X+086826Y+048050X0200Y         S0      
317P52V_HS_FILTER   VIA   -    MD0100PA00X+086826Y+047768X0200Y         S0      
317P52V_HS_FILTER   VIA   -    MD0100PA00X+086526Y+048350X0200Y         S0      
317P52V_HS_FILTER   VIA   -    MD0100PA00X+086826Y+048350X0200Y         S0      
317P52V_HS_FILTER   VIA   -    MD0100PA00X+086531Y+048633X0200Y         S0      
317P52V_HS_FILTER   VIA   -    MD0100PA00X+086831Y+048633X0200Y         S0      
317P52V_HS_FILTER   VIA   -    MD0100PA00X+084243Y+050846X0200Y         S0      
317P52V_HS_FILTER   VIA   -    MD0100PA00X+084526Y+050541X0200Y         S0      
317P52V_HS_FILTER   VIA   -    MD0100PA00X+084243Y+050546X0200Y         S0      
317P52V_HS_FILTER   VIA   -    MD0100PA00X+084526Y+050241X0200Y         S0      
317P52V_HS_FILTER   VIA   -    MD0100PA00X+084243Y+050246X0200Y         S0      
317P52V_HS_FILTER   VIA   -    MD0100PA00X+085108Y+050241X0200Y         S0      
317P52V_HS_FILTER   VIA   -    MD0100PA00X+084826Y+050241X0200Y         S0      
317P52V_HS_FILTER   VIA   -    MD0100PA00X+085408Y+050241X0200Y         S0      
317P52V_HS_FILTER   VIA   -    MD0100PA00X+085108Y+052341X0200Y         S0      
317P52V_HS_FILTER   VIA   -    MD0100PA00X+084826Y+052341X0200Y         S0      
317P52V_HS_FILTER   VIA   -    MD0100PA00X+085408Y+052341X0200Y         S0      
317P52V_HS_FILTER   VIA   -    MD0100PA00X+084243Y+052046X0200Y         S0      
317P52V_HS_FILTER   VIA   -    MD0100PA00X+084526Y+052041X0200Y         S0      
317P52V_HS_FILTER   VIA   -    MD0100PA00X+084526Y+051741X0200Y         S0      
317P52V_HS_FILTER   VIA   -    MD0100PA00X+084243Y+051746X0200Y         S0      
317P52V_HS_FILTER   VIA   -    MD0100PA00X+084526Y+051441X0200Y         S0      
317P52V_HS_FILTER   VIA   -    MD0100PA00X+084243Y+051446X0200Y         S0      
317P52V_HS_FILTER   VIA   -    MD0100PA00X+084526Y+051141X0200Y         S0      
317P52V_HS_FILTER   VIA   -    MD0100PA00X+084243Y+051146X0200Y         S0      
317P52V_HS_FILTER   VIA   -    MD0100PA00X+084526Y+050841X0200Y         S0      
317P52V_HS_FILTER   VIA   -    MD0100PA00X+085408Y+052041X0200Y         S0      
317P52V_HS_FILTER   VIA   -    MD0100PA00X+084826Y+052041X0200Y         S0      
317P52V_HS_FILTER   VIA   -    MD0100PA00X+085108Y+052041X0200Y         S0      
317P52V_HS_FILTER   VIA   -    MD0100PA00X+085108Y+051741X0200Y         S0      
317P52V_HS_FILTER   VIA   -    MD0100PA00X+084826Y+051741X0200Y         S0      
317P52V_HS_FILTER   VIA   -    MD0100PA00X+085408Y+051741X0200Y         S0      
317P52V_HS_FILTER   VIA   -    MD0100PA00X+085108Y+051441X0200Y         S0      
317P52V_HS_FILTER   VIA   -    MD0100PA00X+084826Y+051441X0200Y         S0      
317P52V_HS_FILTER   VIA   -    MD0100PA00X+085408Y+051441X0200Y         S0      
317P52V_HS_FILTER   VIA   -    MD0100PA00X+085108Y+051141X0200Y         S0      
317P52V_HS_FILTER   VIA   -    MD0100PA00X+084826Y+051141X0200Y         S0      
317P52V_HS_FILTER   VIA   -    MD0100PA00X+085408Y+051141X0200Y         S0      
317P52V_HS_FILTER   VIA   -    MD0100PA00X+085108Y+050841X0200Y         S0      
317P52V_HS_FILTER   VIA   -    MD0100PA00X+084826Y+050841X0200Y         S0      
317P52V_HS_FILTER   VIA   -    MD0100PA00X+085408Y+050841X0200Y         S0      
317P52V_HS_FILTER   VIA   -    MD0100PA00X+085108Y+050541X0200Y         S0      
317P52V_HS_FILTER   VIA   -    MD0100PA00X+084826Y+050541X0200Y         S0      
317P52V_HS_FILTER   VIA   -    MD0100PA00X+085408Y+050541X0200Y         S0      
317P52V_HS_FILTER   VIA   -    MD0100PA00X+084526Y+052341X0200Y         S0      
317P52V_HS_FILTER   VIA   -    MD0100PA00X+084243Y+052346X0200Y         S0      
317P52V_HS_FILTER   VIA   -    MD0100PA00X+080271Y+048633X0200Y    R270 S0      
317P52V_HS_FILTER   VIA   -    MD0100PA00X+079966Y+048350X0200Y    R270 S0      
317P52V_HS_FILTER   VIA   -    MD0100PA00X+079971Y+048633X0200Y    R270 S0      
317P52V_HS_FILTER   VIA   -    MD0100PA00X+079666Y+048350X0200Y    R270 S0      
317P52V_HS_FILTER   VIA   -    MD0100PA00X+079671Y+048633X0200Y    R270 S0      
317P52V_HS_FILTER   VIA   -    MD0100PA00X+079666Y+047768X0200Y    R270 S0      
317P52V_HS_FILTER   VIA   -    MD0100PA00X+079666Y+048050X0200Y    R270 S0      
317P52V_HS_FILTER   VIA   -    MD0100PA00X+079666Y+047468X0200Y    R270 S0      
317P52V_HS_FILTER   VIA   -    MD0100PA00X+081766Y+047768X0200Y    R270 S0      
317P52V_HS_FILTER   VIA   -    MD0100PA00X+081766Y+048050X0200Y    R270 S0      
317P52V_HS_FILTER   VIA   -    MD0100PA00X+081766Y+047468X0200Y    R270 S0      
317P52V_HS_FILTER   VIA   -    MD0100PA00X+081471Y+048633X0200Y    R270 S0      
317P52V_HS_FILTER   VIA   -    MD0100PA00X+081466Y+048350X0200Y    R270 S0      
317P52V_HS_FILTER   VIA   -    MD0100PA00X+081166Y+048350X0200Y    R270 S0      
317P52V_HS_FILTER   VIA   -    MD0100PA00X+081171Y+048633X0200Y    R270 S0      
317P52V_HS_FILTER   VIA   -    MD0100PA00X+080866Y+048350X0200Y    R270 S0      
317P52V_HS_FILTER   VIA   -    MD0100PA00X+080871Y+048633X0200Y    R270 S0      
317P52V_HS_FILTER   VIA   -    MD0100PA00X+080566Y+048350X0200Y    R270 S0      
317P52V_HS_FILTER   VIA   -    MD0100PA00X+080571Y+048633X0200Y    R270 S0      
317P52V_HS_FILTER   VIA   -    MD0100PA00X+080266Y+048350X0200Y    R270 S0      
317P52V_HS_FILTER   VIA   -    MD0100PA00X+081466Y+047468X0200Y    R270 S0      
317P52V_HS_FILTER   VIA   -    MD0100PA00X+081466Y+048050X0200Y    R270 S0      
317P52V_HS_FILTER   VIA   -    MD0100PA00X+081466Y+047768X0200Y    R270 S0      
317P52V_HS_FILTER   VIA   -    MD0100PA00X+081166Y+047768X0200Y    R270 S0      
317P52V_HS_FILTER   VIA   -    MD0100PA00X+081166Y+048050X0200Y    R270 S0      
317P52V_HS_FILTER   VIA   -    MD0100PA00X+081166Y+047468X0200Y    R270 S0      
317P52V_HS_FILTER   VIA   -    MD0100PA00X+080866Y+047768X0200Y    R270 S0      
317P52V_HS_FILTER   VIA   -    MD0100PA00X+080866Y+048050X0200Y    R270 S0      
317P52V_HS_FILTER   VIA   -    MD0100PA00X+080866Y+047468X0200Y    R270 S0      
317P52V_HS_FILTER   VIA   -    MD0100PA00X+080566Y+047768X0200Y    R270 S0      
317P52V_HS_FILTER   VIA   -    MD0100PA00X+080566Y+048050X0200Y    R270 S0      
317P52V_HS_FILTER   VIA   -    MD0100PA00X+080566Y+047468X0200Y    R270 S0      
317P52V_HS_FILTER   VIA   -    MD0100PA00X+080266Y+047768X0200Y    R270 S0      
317P52V_HS_FILTER   VIA   -    MD0100PA00X+080266Y+048050X0200Y    R270 S0      
317P52V_HS_FILTER   VIA   -    MD0100PA00X+080266Y+047468X0200Y    R270 S0      
317P52V_HS_FILTER   VIA   -    MD0100PA00X+079966Y+047768X0200Y    R270 S0      
317P52V_HS_FILTER   VIA   -    MD0100PA00X+079966Y+048050X0200Y    R270 S0      
317P52V_HS_FILTER   VIA   -    MD0100PA00X+079966Y+047468X0200Y    R270 S0      
317P52V_HS_FILTER   VIA   -    MD0100PA00X+081766Y+048350X0200Y    R270 S0      
317P52V_HS_FILTER   VIA   -    MD0100PA00X+081771Y+048633X0200Y    R270 S0      
317P52V_HS_FILTER   VIA   -    MD0100PA00X+085931Y+048633X0200Y    R270 S0      
317P52V_HS_FILTER   VIA   -    MD0100PA00X+085626Y+048350X0200Y    R270 S0      
317P52V_HS_FILTER   VIA   -    MD0100PA00X+085631Y+048633X0200Y    R270 S0      
317P52V_HS_FILTER   VIA   -    MD0100PA00X+085326Y+048350X0200Y    R270 S0      
317P52V_HS_FILTER   VIA   -    MD0100PA00X+085331Y+048633X0200Y    R270 S0      
317P52V_HS_FILTER   VIA   -    MD0100PA00X+085326Y+047768X0200Y    R270 S0      
317P52V_HS_FILTER   VIA   -    MD0100PA00X+085326Y+048050X0200Y    R270 S0      
317P52V_HS_FILTER   VIA   -    MD0100PA00X+085326Y+047468X0200Y    R270 S0      
317P52V_HS_FILTER   VIA   -    MD0100PA00X+086226Y+048350X0200Y    R270 S0      
317P52V_HS_FILTER   VIA   -    MD0100PA00X+086231Y+048633X0200Y    R270 S0      
317P52V_HS_FILTER   VIA   -    MD0100PA00X+085926Y+048350X0200Y    R270 S0      
317P52V_HS_FILTER   VIA   -    MD0100PA00X+086226Y+047768X0200Y    R270 S0      
317P52V_HS_FILTER   VIA   -    MD0100PA00X+086226Y+048050X0200Y    R270 S0      
317P52V_HS_FILTER   VIA   -    MD0100PA00X+086226Y+047468X0200Y    R270 S0      
317P52V_HS_FILTER   VIA   -    MD0100PA00X+085926Y+047768X0200Y    R270 S0      
317P52V_HS_FILTER   VIA   -    MD0100PA00X+085926Y+048050X0200Y    R270 S0      
317P52V_HS_FILTER   VIA   -    MD0100PA00X+085926Y+047468X0200Y    R270 S0      
317P52V_HS_FILTER   VIA   -    MD0100PA00X+085626Y+047768X0200Y    R270 S0      
317P52V_HS_FILTER   VIA   -    MD0100PA00X+085626Y+048050X0200Y    R270 S0      
317P52V_HS_FILTER   VIA   -    MD0100PA00X+085626Y+047468X0200Y    R270 S0      
317P52V_HS_FILTER   PC71  -1   MD0420PA00X+026154Y+053900X0620Y0620     S3      
317P52V_HS_FILTER   PC43  -1   MD0420PA00X+041902Y+053900X0620Y0620     S3      
317P52V_HS_FILTER   PC44  -1   MD0420PA00X+037102Y+053900X0620Y0620     S3      
317P52V_HS_FILTER   PC45  -1   MD0420PA00X+032302Y+053900X0620Y0620     S3      
317P52V_HS_FILTER   PC15  -1   MD0420PA00X+057650Y+053900X0620Y0620     S3      
317P52V_HS_FILTER   PC16  -1   MD0420PA00X+052850Y+053900X0620Y0620     S3      
317P52V_HS_FILTER   PC17  -1   MD0420PA00X+048050Y+053900X0620Y0620     S3      
317P52V_HS_FILTER   PC114 -1   MD0420PA00X+068598Y+053900X0620Y0620     S3      
317P52V_HS_FILTER   PU6   -1   MD0630PA00X+072626Y+047720X0930Y0930R270 S3      
317P52V_HS_FILTER   VIA   -    M      A01X+017194Y+051800X0200Y         S2      
017P52V_HS_FILTER   VIA   -    M      A10X+017194Y+051800X0260Y         S2      
017P52V_HS_FILTER         -    MD0100PA00X+017194Y+051800                       
317P52V_HS_FILTER   VIA   -    MD0100PA00X+016894Y+051800X0200Y         S0      
317P52V_HS_FILTER   VIA   -    M      A01X+017194Y+049800X0200Y    R180 S2      
017P52V_HS_FILTER   VIA   -    M      A10X+017194Y+049800X0260Y    R180 S2      
017P52V_HS_FILTER         -    MD0100PA00X+017194Y+049800                       
317P52V_HS_FILTER   VIA   -    MD0100PA00X+016894Y+049800X0200Y    R180 S0      
317P52V_HS_FILTER   VIA   -    M      A01X+021994Y+051800X0200Y         S2      
017P52V_HS_FILTER   VIA   -    M      A10X+021994Y+051800X0260Y         S2      
017P52V_HS_FILTER         -    MD0100PA00X+021994Y+051800                       
317P52V_HS_FILTER   VIA   -    MD0100PA00X+021694Y+051800X0200Y         S0      
317P52V_HS_FILTER   VIA   -    M      A01X+021994Y+049800X0200Y    R180 S2      
017P52V_HS_FILTER   VIA   -    M      A10X+021994Y+049800X0260Y    R180 S2      
017P52V_HS_FILTER         -    MD0100PA00X+021994Y+049800                       
317P52V_HS_FILTER   VIA   -    MD0100PA00X+021694Y+049800X0200Y    R180 S0      
317P52V_HS_FILTER   VIA   -    M      A01X+026794Y+051800X0200Y         S2      
017P52V_HS_FILTER   VIA   -    M      A10X+026794Y+051800X0260Y         S2      
017P52V_HS_FILTER         -    MD0100PA00X+026794Y+051800                       
317P52V_HS_FILTER   VIA   -    MD0100PA00X+026494Y+051800X0200Y         S0      
317P52V_HS_FILTER   VIA   -    M      A01X+026794Y+049800X0200Y    R180 S2      
017P52V_HS_FILTER   VIA   -    M      A10X+026794Y+049800X0260Y    R180 S2      
017P52V_HS_FILTER         -    MD0100PA00X+026794Y+049800                       
317P52V_HS_FILTER   VIA   -    MD0100PA00X+026494Y+049800X0200Y    R180 S0      
317P52V_HS_FILTER   VIA   -    M      A01X+032942Y+051800X0200Y         S2      
017P52V_HS_FILTER   VIA   -    M      A10X+032942Y+051800X0260Y         S2      
017P52V_HS_FILTER         -    MD0100PA00X+032942Y+051800                       
317P52V_HS_FILTER   VIA   -    MD0100PA00X+032642Y+051800X0200Y         S0      
317P52V_HS_FILTER   VIA   -    M      A01X+032942Y+049800X0200Y    R180 S2      
017P52V_HS_FILTER   VIA   -    M      A10X+032942Y+049800X0260Y    R180 S2      
017P52V_HS_FILTER         -    MD0100PA00X+032942Y+049800                       
317P52V_HS_FILTER   VIA   -    MD0100PA00X+032642Y+049800X0200Y    R180 S0      
317P52V_HS_FILTER   VIA   -    M      A01X+037742Y+051800X0200Y         S2      
017P52V_HS_FILTER   VIA   -    M      A10X+037742Y+051800X0260Y         S2      
017P52V_HS_FILTER         -    MD0100PA00X+037742Y+051800                       
317P52V_HS_FILTER   VIA   -    MD0100PA00X+037442Y+051800X0200Y         S0      
317P52V_HS_FILTER   VIA   -    M      A01X+037742Y+049800X0200Y    R180 S2      
017P52V_HS_FILTER   VIA   -    M      A10X+037742Y+049800X0260Y    R180 S2      
017P52V_HS_FILTER         -    MD0100PA00X+037742Y+049800                       
317P52V_HS_FILTER   VIA   -    MD0100PA00X+037442Y+049800X0200Y    R180 S0      
317P52V_HS_FILTER   VIA   -    M      A01X+042542Y+051800X0200Y         S2      
017P52V_HS_FILTER   VIA   -    M      A10X+042542Y+051800X0260Y         S2      
017P52V_HS_FILTER         -    MD0100PA00X+042542Y+051800                       
317P52V_HS_FILTER   VIA   -    MD0100PA00X+042242Y+051800X0200Y         S0      
317P52V_HS_FILTER   VIA   -    M      A01X+042542Y+049800X0200Y    R180 S2      
017P52V_HS_FILTER   VIA   -    M      A10X+042542Y+049800X0260Y    R180 S2      
017P52V_HS_FILTER         -    MD0100PA00X+042542Y+049800                       
317P52V_HS_FILTER   VIA   -    MD0100PA00X+042242Y+049800X0200Y    R180 S0      
317P52V_HS_FILTER   VIA   -    M      A01X+048690Y+051800X0200Y         S2      
017P52V_HS_FILTER   VIA   -    M      A10X+048690Y+051800X0260Y         S2      
017P52V_HS_FILTER         -    MD0100PA00X+048690Y+051800                       
317P52V_HS_FILTER   VIA   -    MD0100PA00X+048390Y+051800X0200Y         S0      
317P52V_HS_FILTER   VIA   -    M      A01X+048690Y+049800X0200Y    R180 S2      
017P52V_HS_FILTER   VIA   -    M      A10X+048690Y+049800X0260Y    R180 S2      
017P52V_HS_FILTER         -    MD0100PA00X+048690Y+049800                       
317P52V_HS_FILTER   VIA   -    MD0100PA00X+048390Y+049800X0200Y    R180 S0      
317P52V_HS_FILTER   VIA   -    M      A01X+053490Y+051800X0200Y         S2      
017P52V_HS_FILTER   VIA   -    M      A10X+053490Y+051800X0260Y         S2      
017P52V_HS_FILTER         -    MD0100PA00X+053490Y+051800                       
317P52V_HS_FILTER   VIA   -    MD0100PA00X+053190Y+051800X0200Y         S0      
317P52V_HS_FILTER   VIA   -    M      A01X+053490Y+049800X0200Y    R180 S2      
017P52V_HS_FILTER   VIA   -    M      A10X+053490Y+049800X0260Y    R180 S2      
017P52V_HS_FILTER         -    MD0100PA00X+053490Y+049800                       
317P52V_HS_FILTER   VIA   -    MD0100PA00X+053190Y+049800X0200Y    R180 S0      
317P52V_HS_FILTER   VIA   -    MD0100PA00X+057990Y+049800X0200Y    R180 S0      
317P52V_HS_FILTER   VIA   -    M      A01X+058290Y+049800X0200Y    R180 S2      
017P52V_HS_FILTER   VIA   -    M      A10X+058290Y+049800X0260Y    R180 S2      
017P52V_HS_FILTER         -    MD0100PA00X+058290Y+049800                       
317P52V_HS_FILTER   VIA   -    MD0100PA00X+057990Y+051800X0200Y         S0      
317P52V_HS_FILTER   VIA   -    M      A01X+058290Y+051800X0200Y         S2      
017P52V_HS_FILTER   VIA   -    M      A10X+058290Y+051800X0260Y         S2      
017P52V_HS_FILTER         -    MD0100PA00X+058290Y+051800                       
317P52V_HS_FILTER   PU2   -1   MD0630PA00X+056878Y+047720X0930Y0930R270 S3      
317P52V_HS_FILTER   PU3   -1   MD0630PA00X+041130Y+047720X0930Y0930R270 S3      
317P52V_HS_FILTER   PU4   -1   MD0630PA00X+025382Y+047720X0930Y0930R270 S3      
317SKU_ID_2         VIA   -    M      A01X+083350Y+026858X0300Y         S1      
017SKU_ID_2         VIA   -    M      A10X+083350Y+026858X0200Y         S1      
017SKU_ID_2               -    MD0100PA00X+083350Y+026858                       
327SKU_ID_2         U4    -20         A10X+083016Y+028800X0140Y0590R180 S2      
327SKU_ID_2         R90   -2   M      A10X+083100Y+027608X0198Y0197R270 S2      
327SKU_ID_2         R93   -1          A10X+083100Y+026608X0198Y0197R090 S2      
327SKU_ID_1         VIA   -    M      A10X+083350Y+028100X0260Y         S2      
327SKU_ID_1         U4    -19         A10X+083272Y+028800X0140Y0590R180 S2      
327SKU_ID_1         R91   -2   M      A10X+083600Y+027608X0198Y0197R270 S2      
327SKU_ID_1         R94   -1          A10X+083600Y+026608X0198Y0197R090 S2      
317SKU_ID_0         VIA   -    M      A01X+084350Y+026858X0300Y         S1      
017SKU_ID_0         VIA   -    M      A10X+084350Y+026858X0200Y         S1      
017SKU_ID_0               -    MD0100PA00X+084350Y+026858                       
327SKU_ID_0         U4    -18         A10X+083528Y+028800X0140Y0590R180 S2      
327SKU_ID_0         R92   -2   M      A10X+084100Y+027608X0198Y0197R270 S2      
327SKU_ID_0         R95   -1          A10X+084100Y+026608X0198Y0197R090 S2      
317m0084            J13   -2    D0670PA00X+076660Y+063069X0850Y    R270 S3      
317m0084            J13   -3    D0670PA00X+076660Y+064069X0850Y    R270 S3      
317m0085            J11   -3    D0670PA00X+108283Y+060254X0850Y    R090 S3      
317m0085            J11   -2    D0670PA00X+108283Y+061254X0850Y    R090 S3      
317GND3             J10   -1   MD0670PA00X+109602Y+063569X0850Y    R090 S3      
317GND3             J13   -1   MD0670PA00X+075342Y+063569X0850Y    R270 S3      
317GND3             J11   -1   MD0670PA00X+109602Y+060754X0850Y    R090 S3      
317GND3             J12   -1   MD0670PA00X+075331Y+060754X0850Y    R270 S3      
317m0086            J12   -2    D0670PA00X+076650Y+061254X0850Y    R270 S3      
317m0086            J12   -3    D0670PA00X+076650Y+060254X0850Y    R270 S3      
317m0087            J10   -2    D0670PA00X+108283Y+063069X0850Y    R090 S3      
317m0087            J10   -3    D0670PA00X+108283Y+064069X0850Y    R090 S3      
317FAN_PWR_EN_BUF   J7    -S12  D0340PA00X+004378Y+033472X0500Y    R270 S3      
327FAN_PWR_EN_BUF   R32   -2          A10X+084300Y+036008X0198Y0197R270 S2      
317m0088            VIA   -    M      A01X+084384Y+035434X0300Y         S1      
017m0088            VIA   -    M      A10X+084384Y+035434X0200Y         S1      
017m0088                  -    MD0100PA00X+084384Y+035434                       
327m0088            U8    -4          A10X+084476Y+034982X0180Y0520     S2      
327m0088            R33   -2          A10X+084750Y+035692X0198Y0197R090 S2      
327m0088            R32   -1   M      A10X+084300Y+035692X0198Y0197R270 S2      
317SMB_MB_PDB_SDA   VIA   -    MD0100PA00X+094317Y+031538X0200Y         S0      
327SMB_MB_PDB_SDA   U1    -6          A10X+093848Y+032260X0140Y0560R180 S2      
327SMB_MB_PDB_SDA   R7    -1   M      A10X+094077Y+031538X0198Y0197     S2      
317SMB_MB_PDB_SDA   VIA   -    M      A01X+094000Y+028380X0300Y         S1      
017SMB_MB_PDB_SDA   VIA   -    M      A10X+094000Y+028380X0200Y         S1      
017SMB_MB_PDB_SDA         -    MD0100PA00X+094000Y+028380                       
327SMB_MB_PDB_SDA   R67   -2          A10X+094000Y+028108X0198Y0197R270 S2      
327SMB_MB_PDB_SCL   VIA   -    M      A10X+095200Y+028650X0260Y         S2      
327SMB_MB_PDB_SCL   R65   -2          A10X+094700Y+028108X0198Y0197R270 S2      
327SMB_MB_PDB_SCL   U1    -3          A10X+093848Y+034017X0140Y0560R180 S2      
327SMB_MB_PDB_SCL   R6    -1   M      A10X+094127Y+034788X0198Y0197     S2      
327m0089            R75   -2          A10X+094000Y+029692X0198Y0197R090 S2      
327m0089            C67   -1   M      A10X+094000Y+028792X0198Y0197R270 S2      
327m0089            R67   -1   M      A10X+094000Y+027792X0198Y0197R270 S2      
327m0089            VIA   -    M      A10X+093768Y+026836X0260Y         S2      
317m0089            J1    -C2   D0402PA00X+082256Y+012941X0602Y    R270 S3      
327m0090            R74   -2          A10X+094700Y+029692X0198Y0197R090 S2      
327m0090            R65   -1   M      A10X+094700Y+027792X0198Y0197R270 S2      
327m0090            VIA   -    M      A10X+094520Y+027266X0260Y         S2      
317m0090            J1    -C1   D0402PA00X+083256Y+012941X0602Y    R270 S3      
327m0090            C66   -1   M      A10X+094700Y+028792X0198Y0197R270 S2      
317GPU_HSC_EN       VIA   -    MD0100PA00X+088800Y+028348X0200Y         S0      
327GPU_HSC_EN       R71   -2          A10X+088800Y+028108X0198Y0197R270 S2      
317GPU_HSC_EN       VIA   -    MD0100PA00X+077910Y+032682X0200Y         S0      
317GPU_HSC_EN       J7    -S14  D0340PA00X+004378Y+032472X0500Y    R270 S3      
327SMB_FRU_CLK      VIA   -    M      A10X+087100Y+034800X0260Y         S2      
327SMB_FRU_CLK      U10   -6          A10X+087000Y+033890X0220Y0680     S2      
327SMB_FRU_CLK      R42   -1          A10X+086900Y+035292X0198Y0197R270 S2      
327SMB_FRU_DAT      VIA   -    M      A10X+086000Y+034800X0260Y         S2      
327SMB_FRU_DAT      U10   -5          A10X+086500Y+033890X0220Y0680     S2      
327SMB_FRU_DAT      R41   -1          A10X+086450Y+035292X0198Y0197R270 S2      
317MB_MISC_I2C_EN   VIA   -    M      A01X+093336Y+034484X0300Y         S1      
017MB_MISC_I2C_EN   VIA   -    M      A10X+093336Y+034484X0200Y         S1      
017MB_MISC_I2C_EN         -    MD0100PA00X+093336Y+034484                       
327MB_MISC_I2C_EN   R3    -2          A10X+093320Y+034781X0198Y0197R090 S2      
327MB_MISC_I2C_EN   U1    -1          A10X+093336Y+034017X0140Y0560R180 S2      
327m0091            PR65  -1   M      A10X+040482Y+030042X0180Y0200R090 S2      
327m0091            PR323 -2          A10X+072400Y+030358X0198Y0197R270 S2      
327m0091            PR324 -1   M      A10X+040900Y+030358X0198Y0197R090 S2      
317m0091            PU3   -14   D0360PA00X+040492Y+026720X0520Y    R270 S3      
327SMB_BRICK1_SDA   R171  -2          A10X+039058Y+030050X0198Y0197R180 S2      
317SMB_BRICK1_SDA   PU3   -10   D0360PA00X+037342Y+026720X0520Y    R270 S3      
327BRICK1_PMBADD    PR73  -2          A10X+039705Y+030042X0198Y0197R090 S2      
317BRICK1_PMBADD    PU3   -13   D0360PA00X+039705Y+026720X0520Y    R270 S3      
327m0092            R172  -2          A10X+037308Y+030050X0198Y0197R180 S2      
317m0092            PU3   -11   D0360PA00X+038130Y+026720X0520Y    R270 S3      
327m0093            PR67  -1          A10X+036555Y+030042X0198Y0197R270 S2      
317m0093            PU3   -9    D0360PA00X+036555Y+026720X0520Y    R270 S3      
327SMB_BRICK1_SCL   R173  -2          A10X+038158Y+030050X0198Y0197R180 S2      
317SMB_BRICK1_SCL   PU3   -12   D0360PA00X+038917Y+026720X0520Y    R270 S3      
327PCA9555_A2       VIA   -    M      A10X+082750Y+031850X0260Y         S2      
327PCA9555_A2       U4    -3          A10X+082504Y+031100X0140Y0590R180 S2      
327PCA9555_A2       R23   -1   M      A10X+082750Y+032342X0198Y0197R270 S2      
327PCA9555_A2       R20   -2          A10X+082350Y+032342X0198Y0197R090 S2      
327m0094            R170  -2          A10X+038130Y+045858X0198Y0197R270 S2      
317m0094            PU3   -2    D0630PA00X+038130Y+047720X0930Y    R270 S3      
317PCA9555_A1       VIA   -    M      A01X+081950Y+031850X0300Y         S1      
017PCA9555_A1       VIA   -    M      A10X+081950Y+031850X0200Y         S1      
017PCA9555_A1             -    MD0100PA00X+081950Y+031850                       
327PCA9555_A1       U4    -2          A10X+082248Y+031100X0140Y0590R180 S2      
327PCA9555_A1       R22   -1   M      A10X+081950Y+032342X0198Y0197R270 S2      
327PCA9555_A1       R19   -2          A10X+081550Y+032342X0198Y0197R090 S2      
327m0095            VIA   -    M      A10X+079850Y+027260X0260Y         S2      
317m0095            VIA   -    MD0100PA00X+070004Y+025896X0200Y         S0      
317m0095            VIA   -    MD0100PA00X+069441Y+029550X0200Y         S0      
327m0095            R193  -2          A10X+069441Y+031050X0198Y0197     S2      
327m0095            R197  -1   M      A10X+069441Y+030050X0198Y0197R180 S2      
327m0095            C72   -1   M      A10X+069441Y+030550X0198Y0197R180 S2      
327m0095            U4    -7          A10X+083528Y+031100X0140Y0590R180 S2      
317PCA9555_A0       VIA   -    M      A01X+082760Y+028350X0300Y         S1      
017PCA9555_A0       VIA   -    M      A10X+082760Y+028350X0200Y         S1      
017PCA9555_A0             -    MD0100PA00X+082760Y+028350                       
327PCA9555_A0       U4    -21         A10X+082760Y+028800X0140Y0590R180 S2      
327PCA9555_A0       R18   -2   M      A10X+082600Y+027608X0198Y0197R270 S2      
327PCA9555_A0       R21   -1          A10X+082600Y+026608X0198Y0197R090 S2      
327m0096            VIA   -    M      A10X+006974Y+035004X0260Y         S2      
317m0096            J7    -S7   D0340PA00X+003378Y+034472X0500Y    R270 S3      
327m0096            R77   -2          A10X+015192Y+035050X0198Y0197     S2      
317m0097            J7    -S8   D0340PA00X+003878Y+034972X0500Y    R270 S3      
327m0097            R76   -2          A10X+015192Y+034650X0198Y0197     S2      
327FRU_ADDR1        VIA   -    M      A10X+087250Y+030191X0260Y         S2      
327FRU_ADDR1        U10   -2          A10X+087500Y+031810X0220Y0680     S2      
327FRU_ADDR1        R44   -2          A10X+087500Y+029708X0198Y0197R270 S2      
327FRU_ADDR1        R39   -2   M      A10X+087500Y+031008X0198Y0197R270 S2      
327PU_U4_PIN1       VIA   -    M      A10X+081500Y+031850X0260Y         S2      
327PU_U4_PIN1       U4    -1          A10X+081992Y+031100X0140Y0590R180 S2      
327PU_U4_PIN1       R17   -2          A10X+081150Y+032342X0198Y0197R090 S2      
317FRU_ADDR0        VIA   -    M      A01X+088000Y+031286X0300Y         S1      
017FRU_ADDR0        VIA   -    M      A10X+088000Y+031286X0200Y         S1      
017FRU_ADDR0              -    MD0100PA00X+088000Y+031286                       
327FRU_ADDR0        U10   -1          A10X+088000Y+031810X0220Y0680     S2      
327FRU_ADDR0        R45   -2          A10X+088000Y+029708X0198Y0197R270 S2      
327FRU_ADDR0        R40   -2   M      A10X+088000Y+031008X0198Y0197R270 S2      
327m0098            R175  -2          A10X+036992Y+030950X0198Y0197     S2      
327m0098            C58   -1   M      A10X+036992Y+030500X0198Y0197R180 S2      
327m0098            R172  -1   M      A10X+036992Y+030050X0198Y0197R180 S2      
327m0098            VIA   -    M      A10X+036992Y+028736X0260Y         S2      
327m0098            U4    -6          A10X+083272Y+031100X0140Y0590R180 S2      
317m0099            VIA   -    M      A01X+082700Y+035250X0300Y         S1      
017m0099            VIA   -    M      A10X+082700Y+035250X0200Y         S1      
017m0099                  -    MD0100PA00X+082700Y+035250                       
327m0099            U6    -4          A10X+082594Y+034974X0170Y0240     S2      
327m0099            R29   -2   M      A10X+082700Y+035492X0198Y0197R090 S2      
327m0099            R30   -1          A10X+082150Y+035492X0198Y0197R270 S2      
327m0100            R199  -2          A10X+092600Y+027792X0198Y0197R090 S2      
327m0100            VIA   -    M      A10X+092090Y+027282X0260Y         S2      
317m0100            J1    -A3   D0402PA00X+081256Y+014941X0602Y    R270 S3      
327GPU_HSC_R_EN     R71   -1   M      A10X+088800Y+027792X0198Y0197R270 S2      
327GPU_HSC_R_EN     C18   -1          A10X+088400Y+027792X0198Y0197R270 S2      
327GPU_HSC_R_EN     VIA   -    M      A10X+087904Y+027158X0260Y         S2      
317GPU_HSC_R_EN     J1    -D2   D0402PA00X+082256Y+011941X0602Y    R270 S3      
327FAN_PWR_R_EN     R70   -1   M      A10X+090900Y+027792X0198Y0197R270 S2      
327FAN_PWR_R_EN     VIA   -    M      A10X+090394Y+027286X0260Y         S2      
317FAN_PWR_R_EN     J1    -D1   D0402PA00X+083256Y+011941X0602Y    R270 S3      
327FAN_PWR_R_EN     C17   -1          A10X+090500Y+027792X0198Y0197R270 S2      
327LED_D1_R5        VIA   -    M      A01X+084000Y+033750X0300Y         S1      
327LED_D1_R5        R63   -2          A01X+083280Y+033750X0400Y0630     S1      
327LED_D1_R5        D1    -A          A01X+083437Y+032900X0240Y0280R180 S1      
317LED_D2_R3        VIA   -    M      A01X+079490Y+026598X0200Y         S2      
017LED_D2_R3        VIA   -    M      A10X+079490Y+026598X0260Y         S2      
017LED_D2_R3              -    MD0100PA00X+079490Y+026598                       
327LED_D2_R3        R61   -2          A01X+079235Y+026518X0198Y0197R090 S1      
327LED_D2_R3        D2    -A          A01X+079785Y+026598X0240Y0280R270 S1      
327m0101            R78   -2          A10X+015192Y+033550X0198Y0197     S2      
327m0101            VIA   -    M      A10X+006060Y+033550X0260Y         S2      
317m0101            J7    -S6   D0340PA00X+003878Y+033972X0500Y    R270 S3      
327m0102            R79   -2          A10X+015192Y+033100X0198Y0197     S2      
317m0102            J7    -S5   D0340PA00X+003378Y+033472X0500Y    R270 S3      
327P52V_HS1_OV      PR2   -2          A10X+114800Y+020626X0440Y0540R270 S2      
317P52V_HS1_OV      VIA   -    M      A01X+111450Y+018870X0200Y         S2      
017P52V_HS1_OV      VIA   -    M      A10X+111450Y+018870X0260Y         S2      
017P52V_HS1_OV            -    MD0100PA00X+111450Y+018870                       
327P52V_HS1_OV      PR9   -1          A01X+111000Y+019242X0198Y0197R090 S1      
327P52V_HS1_OV      PC1   -1   M      A01X+111400Y+019242X0198Y0197R090 S1      
327P52V_HS1_OV      PU7   -47         A01X+112124Y+018028X0120Y0330     S1      
317P52V_HS1_OV      VIA   -    MD0100PA00X+103700Y+014630X0200Y         S0      
327P52V_HS1_OV      PU1   -12         A01X+103757Y+014938X0110Y0300     S1      
327m0103            VIA   -    M      A10X+109600Y+016500X0260Y         S2      
327m0103            PR31  -2          A10X+110042Y+016500X0198Y0197     S2      
327m0103            PC12  -1          A10X+109108Y+016400X0198Y0197     S2      
327m0103            PR37  -1   M      A10X+109108Y+016750X0198Y0197     S2      
327m0104            VIA   -    M      A10X+109600Y+017050X0260Y         S2      
327m0104            PC11  -1   M      A10X+109108Y+017100X0198Y0197     S2      
327m0104            PR36  -1          A10X+109108Y+017450X0198Y0197     S2      
327m0104            PR93  -2          A10X+110042Y+016850X0198Y0197     S2      
327P52V_HS1_DV_DT   VIA   -    M      A01X+115875Y+014475X0300Y         S1      
327P52V_HS1_DV_DT   PC13  -1          A01X+115158Y+014591X0400Y0500     S1      
327P52V_HS1_DV_DT   PR32  -2          A01X+115259Y+013916X0440Y0540R270 S1      
327P52V_HS1_VCP     VIA   -           A01X+115384Y+016110X0300Y         S1      
327P52V_HS1_VCP     PC559 -2          A01X+116120Y+016020X0460Y0620R090 S1      
327P52V_HS1_VCP     PU7   -29         A01X+114762Y+016375X0120Y0330R270 S1      
327P52V_HS1_TEMPN   PU7   -43         A01X+112912Y+018028X0120Y0330     S1      
317P52V_HS1_TEMPN   VIA   -    MD0100PA00X+112907Y+019550X0200Y         S0      
327P52V_HS1_TEMPN   PC560 -2   M      A01X+112907Y+019276X0198Y0197     S1      
317P52V_HS1_TEMPN   VIA   -    M      A01X+111729Y+022424X0200Y         S2      
017P52V_HS1_TEMPN   VIA   -    M      A10X+111729Y+022424X0260Y         S2      
017P52V_HS1_TEMPN         -    MD0100PA00X+111729Y+022424                       
327P52V_HS1_TEMPN   PR6968-1          A01X+111489Y+022424X0180Y0200     S1      
327P52V_HS1_MCB     VIA   -    M      A01X+111250Y+015100X0300Y         S1      
327P52V_HS1_MCB     PU7   -12         A01X+111652Y+015587X0120Y0330R270 S1      
327P52V_HS1_MCB     PR35  -1          A01X+110450Y+014208X0198Y0197R270 S1      
317P52V_HS1_ISET    VIA   -    MD0100PA00X+110000Y+020370X0200Y         S0      
317P52V_HS1_ISET    VIA   -    MD0100PA00X+109750Y+020370X0200Y         S0      
327P52V_HS1_ISET    PR18  -2          A10X+112026Y+021450X0440Y0540R180 S2      
327P52V_HS1_ISET    PR19  -2          A01X+109874Y+019950X0440Y0540R180 S1      
327P52V_HS1_ISET    VIA   -           A01X+110517Y+018263X0300Y         S1      
327P52V_HS1_ISET    PC561 -1          A01X+109954Y+018360X0198Y0197R180 S1      
327P52V_HS1_ISET    PR21  -1          A01X+109958Y+018800X0198Y0197R180 S1      
327P52V_HS1_ISET    PU7   -1          A01X+111652Y+017753X0120Y0330R270 S1      
327P52V_HS1_ISET    PR6933-1          A01X+109958Y+017950X0198Y0197R180 S1      
327m0105            VIA   -    M      A01X+110850Y+017600X0300Y         S1      
327m0105            PU7   -2          A01X+111652Y+017556X0120Y0330R270 S1      
327m0105            PR20  -1          A01X+109608Y+017350X0198Y0197R180 S1      
327m0105            PR6934-1   M      A01X+110042Y+017350X0198Y0197     S1      
327P52V_HS1_VREG    PC10  -1          A01X+113300Y+019242X0198Y0197R090 S1      
327P52V_HS1_VREG    VIA   -    M      A01X+113109Y+018691X0300Y         S1      
327P52V_HS1_VREG    PU7   -42         A01X+113109Y+018028X0120Y0330     S1      
327P52V_HS1_GATE5   PQ5   -G          A01X+107616Y+031794X0520Y1220R270 S1      
327P52V_HS1_GATE5   PR15  -2          A01X+106450Y+031794X0280Y0320R180 S1      
317P52V_HS1_GATE5   VIA   -           A01X+106768Y+031794X0200Y         S2      
017P52V_HS1_GATE5   VIA   -           A10X+106768Y+031794X0260Y         S2      
017P52V_HS1_GATE5         -     D0100PA00X+106768Y+031794                       
327P52V_HS1_EN      R5918 -1          A10X+105724Y+011150X0440Y0540R180 S2      
327P52V_HS1_EN      D12   -C   M      A10X+106187Y+010050X0670Y0990R090 S2      
327P52V_HS1_EN      VIA   -    M      A10X+106350Y+011150X0260Y         S2      
327P52V_HS1_EN      U37   -D   M      A10X+107750Y+010056X0320Y0360R180 S2      
327P52V_HS1_EN      PR6973-1          A01X+108642Y+010300X0198Y0197     S1      
317P52V_HS1_EN      VIA   -    MD0100PA00X+108700Y+010000X0200Y         S0      
317P52V_HS1_EN      JP3   -2    D0460PA00X+116100Y+009040X0660Y         S3      
327P52V_HS1_VCC     PR5   -2          A01X+115500Y+019320X0400Y0630R270 S1      
327P52V_HS1_VCC     VIA   -           A01X+113781Y+018759X0300Y         S1      
327P52V_HS1_VCC     PC558 -1          A01X+114064Y+019380X0460Y0620R270 S1      
327P52V_HS1_VCC     PU7   -41         A01X+113699Y+018028X0120Y0330     S1      
327P52V_HS1_VCC     PU7   -24         A01X+114487Y+015312X0120Y0330     S1      
327P52V_HS1_VCC     PU7   -23         A01X+114290Y+015312X0120Y0330     S1      
327P52V_HS1_VCC     PU7   -22         A01X+114093Y+015312X0120Y0330     S1      
327P52V_HS1_VCC     PU7   -21         A01X+113896Y+015312X0120Y0330     S1      
327P52V_HS1_VCC     PU7   -20         A01X+113699Y+015312X0120Y0330     S1      
317P52V_HS1_VCC     VIA   -    MD0100PA00X+114000Y+016110X0200Y         S0      
317P52V_HS1_VCC     VIA   -    MD0100PA00X+114000Y+017230X0200Y         S0      
317P52V_HS1_VCC     VIA   -    MD0100PA00X+113630Y+017230X0200Y         S0      
317P52V_HS1_VCC     VIA   -    MD0100PA00X+113630Y+016110X0200Y         S0      
327P52V_HS1_VCC     PU7   -PAD2M      A01X+113818Y+016670X0590Y1340     S1      
327P52V_HS1_ADR0    R5905 -2   M      A10X+104958Y+013750X0198Y0197R180 S2      
327P52V_HS1_ADR0    R5907 -1   M      A10X+108250Y+018142X0198Y0197R270 S2      
327P52V_HS1_ADR0    R158  -1   M      A10X+107700Y+018142X0198Y0197R270 S2      
327P52V_HS1_ADR0    R156  -2   M      A10X+110358Y+018000X0198Y0197R180 S2      
317P52V_HS1_ADR0    VIA   -    M      A01X+111313Y+016572X0200Y         S2      
017P52V_HS1_ADR0    VIA   -    M      A10X+111313Y+016572X0260Y         S2      
017P52V_HS1_ADR0          -    MD0100PA00X+111313Y+016572                       
327P52V_HS1_ADR0    PU7   -7          A01X+111652Y+016572X0120Y0330R270 S1      
317P52V_HS1_ADR0    VIA   -    MD0100PA00X+104716Y+014149X0200Y         S0      
327P52V_HS1_ADR0    PU1   -16         A01X+104544Y+014938X0110Y0300     S1      
327LED_D2_R2        R61   -1          A01X+079235Y+026203X0198Y0197R090 S1      
327LED_D2_R2        R58   -2          A01X+078735Y+026203X0198Y0197R270 S1      
317LED_D2_R2        VIA   -    M      A01X+079000Y+025961X0200Y         S2      
017LED_D2_R2        VIA   -    M      A10X+079000Y+025961X0260Y         S2      
017LED_D2_R2              -    MD0100PA00X+079000Y+025961                       
317LED_D2_R1        VIA   -    M      A01X+078486Y+026518X0200Y         S2      
017LED_D2_R1        VIA   -    M      A10X+078486Y+026518X0260Y         S2      
017LED_D2_R1              -    MD0100PA00X+078486Y+026518                       
327LED_D2_R1        R56   -2          A01X+078235Y+026518X0198Y0197R090 S1      
327LED_D2_R1        R58   -1          A01X+078735Y+026518X0198Y0197R270 S1      
327m0106            PR31  -1          A10X+110358Y+016500X0198Y0197     S2      
317m0106            VIA   -    M      A01X+111080Y+017000X0300Y         S1      
017m0106            VIA   -    M      A10X+111080Y+017000X0200Y         S1      
017m0106                  -    MD0100PA00X+111080Y+017000                       
327m0106            PU7   -5          A01X+111652Y+016965X0120Y0330R270 S1      
327LED_D1_R4        VIA   -    M      A01X+081405Y+034145X0300Y         S1      
327LED_D1_R4        R62   -2          A01X+082020Y+034550X0400Y0630R180 S1      
327LED_D1_R4        R63   -1          A01X+082020Y+033750X0400Y0630     S1      
327m0107            PR93  -1          A10X+110358Y+016850X0198Y0197     S2      
317m0107            VIA   -    M      A01X+111337Y+017162X0200Y         S2      
017m0107            VIA   -    M      A10X+111337Y+017162X0260Y         S2      
017m0107                  -    MD0100PA00X+111337Y+017162                       
327m0107            PU7   -4          A01X+111652Y+017162X0120Y0330R270 S1      
327LED_D1_R3        VIA   -    M      A01X+084000Y+034550X0300Y         S1      
327LED_D1_R3        R60   -2          A01X+083280Y+036060X0400Y0630     S1      
327LED_D1_R3        R62   -1          A01X+083280Y+034550X0400Y0630R180 S1      
327LED_D1_R2        VIA   -    M      A01X+081310Y+036860X0300Y         S1      
327LED_D1_R2        R57   -2          A01X+082020Y+036860X0400Y0630R180 S1      
327LED_D1_R2        R60   -1          A01X+082020Y+036060X0400Y0630     S1      
327P52V_HS1_GATE6   PQ6   -G          A01X+107616Y+027044X0520Y1220R270 S1      
327P52V_HS1_GATE6   PR16  -2          A01X+106450Y+027044X0280Y0320R180 S1      
317P52V_HS1_GATE6   VIA   -           A01X+106770Y+027044X0200Y         S2      
017P52V_HS1_GATE6   VIA   -           A10X+106770Y+027044X0260Y         S2      
017P52V_HS1_GATE6         -     D0100PA00X+106770Y+027044                       
327LED_D1_R1        VIA   -    M      A01X+084000Y+036300X0300Y         S1      
327LED_D1_R1        R55   -2          A01X+084000Y+036970X0400Y0630R270 S1      
327LED_D1_R1        R57   -1          A01X+083280Y+036860X0400Y0630R180 S1      
327P52V_HS1_GATE4   PR14  -2          A01X+106450Y+036544X0280Y0320     S1      
327P52V_HS1_GATE4   PQ4   -G          A01X+107616Y+036544X0520Y1220R270 S1      
317P52V_HS1_GATE4   VIA   -           A01X+106771Y+036544X0200Y         S2      
017P52V_HS1_GATE4   VIA   -           A10X+106771Y+036544X0260Y         S2      
017P52V_HS1_GATE4         -     D0100PA00X+106771Y+036544                       
327P52V_HS1_VCAP    VIA   -    M      A10X+109550Y+018350X0260Y         S2      
317P52V_HS1_VCAP    VIA   -    M      A01X+110800Y+017200X0200Y         S2      
017P52V_HS1_VCAP    VIA   -    M      A10X+110800Y+017200X0260Y         S2      
017P52V_HS1_VCAP          -    MD0100PA00X+110800Y+017200                       
327P52V_HS1_VCAP    PU7   -3          A01X+111652Y+017359X0120Y0330R270 S1      
327P52V_HS1_VCAP    PR6934-2          A01X+110358Y+017350X0198Y0197     S1      
327P52V_HS1_VCAP    PC562 -1          A01X+110140Y+016850X0280Y0320R090 S1      
327P52V_HS1_VCAP    R157  -1          A10X+110042Y+018350X0198Y0197R180 S2      
327P52V_HS1_VCAP    R156  -1          A10X+110042Y+018000X0198Y0197R180 S2      
317P52V_HS1_VCAP    VIA   -    MD0100PA00X+109402Y+017950X0200Y         S0      
327P52V_HS1_VCAP    PR6933-2          A01X+109642Y+017950X0198Y0197R180 S1      
327P52V_HS1_UVH     PR4   -2          A10X+115550Y+020626X0440Y0540R270 S2      
317P52V_HS1_UVH     VIA   -    M      A01X+112350Y+018700X0200Y         S2      
017P52V_HS1_UVH     VIA   -    M      A10X+112350Y+018700X0260Y         S2      
017P52V_HS1_UVH           -    MD0100PA00X+112350Y+018700                       
327P52V_HS1_UVH     PR6931-1          A01X+111800Y+019242X0198Y0197R090 S1      
327P52V_HS1_UVH     PC557 -1   M      A01X+112200Y+019242X0198Y0197R090 S1      
327P52V_HS1_UVH     PU7   -45         A01X+112518Y+018028X0120Y0330     S1      
327P52V_HS1_RND     PC9   -1          A01X+110600Y+019242X0198Y0197R090 S1      
327P52V_HS1_RND     VIA   -    M      A01X+111092Y+018750X0300Y         S1      
327P52V_HS1_RND     PU7   -48         A01X+111927Y+018028X0120Y0330     S1      
327m0108            R145  -2          A01X+110011Y+014314X0198Y0197     S1      
327m0108            VIA   -    M      A01X+110500Y+014750X0300Y         S1      
327m0108            PU7   -11         A01X+111652Y+015784X0120Y0330R270 S1      
317P3V3_AUX         VIA   -    MD0100PA00X+081158Y+034400X0200Y         S0      
327P3V3_AUX         R126  -2          A10X+081158Y+034100X0198Y0197R180 S2      
327P3V3_AUX         R5891 -1          A01X+016604Y+024540X0198Y0197R270 S1      
327P3V3_AUX         R5897 -2          A01X+017004Y+024540X0198Y0197R090 S1      
317P3V3_AUX         VIA   -    MD0100PA00X+016984Y+024780X0200Y    R270 S0      
317P3V3_AUX         VIA   -    MD0100PA00X+016584Y+024780X0200Y    R270 S0      
327P3V3_AUX         C48   -1   M      A10X+074808Y+036150X0198Y0197     S2      
327P3V3_AUX         U25   -20         A10X+076028Y+035952X0160Y0440R090 S2      
317P3V3_AUX         VIA   -    MD0100PA00X+074808Y+036650X0200Y         S0      
327P3V3_AUX         R98   -1          A10X+080058Y+036200X0198Y0197     S2      
317P3V3_AUX         VIA   -    MD0100PA00X+080298Y+036200X0200Y         S0      
327P3V3_AUX         R29   -1          A10X+082700Y+035808X0198Y0197R090 S2      
317P3V3_AUX         VIA   -    MD0100PA00X+082700Y+036048X0200Y    R270 S0      
327P3V3_AUX         C7    -2   M      A10X+083250Y+035492X0198Y0197R090 S2      
327P3V3_AUX         U6    -5          A10X+083106Y+034974X0170Y0240     S2      
317P3V3_AUX         VIA   -    MD0100PA00X+082950Y+035492X0200Y         S0      
317P3V3_AUX         VIA   -    MD0100PA00X+074250Y+035320X0200Y         S0      
327P3V3_AUX         R131  -2          A10X+074492Y+035320X0198Y0197     S2      
327P3V3_AUX         R132  -2          A10X+074492Y+034770X0198Y0197     S2      
317P3V3_AUX         VIA   -    MD0100PA00X+074250Y+034770X0200Y         S0      
327P3V3_AUX         VIA   -    M      A10X+043200Y+042760X0260Y         S2      
327P3V3_AUX         VIA   -    M      A10X+057592Y+042550X0260Y         S2      
327P3V3_AUX         R201  -1          A10X+041844Y+043350X0198Y0197R180 S2      
327P3V3_AUX         R168  -1          A10X+057592Y+043350X0198Y0197R180 S2      
317P3V3_AUX         VIA   -    MD0100PA00X+070220Y+035600X0200Y         S0      
317P3V3_AUX         VIA   -    MD0100PA00X+074250Y+033450X0200Y         S0      
327P3V3_AUX         R127  -2          A10X+074492Y+033450X0198Y0197     S2      
317P3V3_AUX         VIA   -    MD0100PA00X+074250Y+032450X0200Y         S0      
327P3V3_AUX         R105  -2          A10X+074492Y+032450X0198Y0197     S2      
317P3V3_AUX         VIA   -    MD0100PA00X+074250Y+032850X0200Y         S0      
327P3V3_AUX         R128  -2          A10X+074492Y+032850X0198Y0197     S2      
317P3V3_AUX         VIA   -    MD0100PA00X+070896Y+031050X0200Y         S0      
327P3V3_AUX         R194  -1          A10X+070656Y+031050X0198Y0197     S2      
317P3V3_AUX         VIA   -    MD0100PA00X+069996Y+031050X0200Y         S0      
327P3V3_AUX         R193  -1          A10X+069756Y+031050X0198Y0197     S2      
317P3V3_AUX         VIA   -    MD0100PA00X+069096Y+031050X0200Y         S0      
327P3V3_AUX         R192  -1          A10X+068856Y+031050X0198Y0197     S2      
327P3V3_AUX         R161  -1          A10X+054908Y+031050X0198Y0197     S2      
317P3V3_AUX         VIA   -    MD0100PA00X+055148Y+031050X0200Y         S0      
327P3V3_AUX         R162  -1          A10X+054008Y+031050X0198Y0197     S2      
317P3V3_AUX         VIA   -    MD0100PA00X+054248Y+031050X0200Y         S0      
327P3V3_AUX         R163  -1          A10X+053108Y+031050X0198Y0197     S2      
317P3V3_AUX         VIA   -    MD0100PA00X+053348Y+031050X0200Y         S0      
327P3V3_AUX         R174  -1          A10X+039058Y+030950X0198Y0197     S2      
317P3V3_AUX         VIA   -    MD0100PA00X+039298Y+030950X0200Y         S0      
327P3V3_AUX         R176  -1          A10X+038158Y+030950X0198Y0197     S2      
317P3V3_AUX         VIA   -    MD0100PA00X+038398Y+030950X0200Y         S0      
327P3V3_AUX         R175  -1          A10X+037308Y+030950X0198Y0197     S2      
317P3V3_AUX         VIA   -    MD0100PA00X+037550Y+030950X0200Y         S0      
327P3V3_AUX         R203  -1          A10X+036100Y+030358X0198Y0197R090 S2      
317P3V3_AUX         VIA   -    MD0100PA00X+036100Y+030598X0200Y         S0      
327P3V3_AUX         R183  -1          A10X+023358Y+030950X0198Y0197     S2      
317P3V3_AUX         VIA   -    MD0100PA00X+023598Y+030950X0200Y         S0      
327P3V3_AUX         R182  -1          A10X+022458Y+030950X0198Y0197     S2      
317P3V3_AUX         VIA   -    MD0100PA00X+022698Y+030950X0200Y         S0      
327P3V3_AUX         R181  -1          A10X+021608Y+030950X0198Y0197     S2      
317P3V3_AUX         VIA   -    MD0100PA00X+021850Y+030950X0200Y         S0      
317P3V3_AUX         VIA   -    MD0100PA00X+085600Y+027052X0200Y         S0      
327P3V3_AUX         R135  -1          A10X+085600Y+027292X0198Y0197R270 S2      
317P3V3_AUX         VIA   -    MD0100PA00X+082600Y+027052X0200Y    R180 S0      
327P3V3_AUX         R18   -1          A10X+082600Y+027292X0198Y0197R270 S2      
317P3V3_AUX         VIA   -    MD0100PA00X+083600Y+027050X0200Y    R270 S0      
327P3V3_AUX         R91   -1          A10X+083600Y+027292X0198Y0197R270 S2      
317P3V3_AUX         VIA   -    MD0100PA00X+080350Y+025952X0200Y         S0      
327P3V3_AUX         R59   -1          A01X+080350Y+026192X0198Y0197R090 S1      
327P3V3_AUX         R5909 -1          A10X+080650Y+027942X0198Y0197R270 S2      
317P3V3_AUX         VIA   -    MD0100PA00X+080390Y+027942X0200Y         S0      
327P3V3_AUX         R150  -1          A01X+110850Y+013892X0198Y0197R090 S1      
317P3V3_AUX         VIA   -    MD0100PA00X+110850Y+013650X0200Y         S0      
327P3V3_AUX         R152  -1          A10X+111000Y+014192X0198Y0197R270 S2      
327P3V3_AUX         R146  -1          A01X+109689Y+015610X0198Y0197     S1      
327P3V3_AUX         R147  -1   M      A01X+109689Y+015186X0198Y0197     S1      
317P3V3_AUX         VIA   -    MD0100PA00X+109449Y+015186X0200Y         S0      
327P3V3_AUX         PC112 -1          A01X+075292Y+006850X0198Y0197     S1      
327P3V3_AUX         PC104 -1   M      A01X+075292Y+002750X0198Y0197     S1      
327P3V3_AUX         PL2   -2          A01X+074102Y+005100X0848Y1300     S1      
327P3V3_AUX         PR90  -2   M      A01X+069758Y+003200X0198Y0197     S1      
327P3V3_AUX         PR87  -1          A01X+070142Y+003200X0198Y0197     S1      
327P3V3_AUX         PC111 -2   M      A01X+069758Y+002700X0198Y0197     S1      
317P3V3_AUX         VIA   -    MD0100PA00X+074976Y+005560X0200Y         S0      
317P3V3_AUX         VIA   -    MD0100PA00X+075256Y+005560X0200Y         S0      
317P3V3_AUX         VIA   -    MD0100PA00X+074716Y+005550X0200Y         S0      
317P3V3_AUX         VIA   -    MD0100PA00X+074976Y+004710X0200Y         S0      
317P3V3_AUX         VIA   -    MD0100PA00X+075256Y+004710X0200Y         S0      
317P3V3_AUX         VIA   -    MD0100PA00X+074716Y+004700X0200Y         S0      
317P3V3_AUX         VIA   -    MD0100PA00X+074976Y+003860X0200Y         S0      
317P3V3_AUX         VIA   -    MD0100PA00X+075256Y+003860X0200Y         S0      
317P3V3_AUX         VIA   -    MD0100PA00X+074716Y+003850X0200Y         S0      
317P3V3_AUX         VIA   -    MD0100PA00X+074976Y+003010X0200Y         S0      
317P3V3_AUX         VIA   -    MD0100PA00X+075256Y+003010X0200Y         S0      
317P3V3_AUX         VIA   -    MD0100PA00X+074716Y+003000X0200Y         S0      
317P3V3_AUX         VIA   -    MD0100PA00X+075030Y+002720X0200Y         S0      
317P3V3_AUX         VIA   -    MD0100PA00X+074976Y+006410X0200Y         S0      
317P3V3_AUX         VIA   -    MD0100PA00X+075256Y+006410X0200Y         S0      
317P3V3_AUX         VIA   -    MD0100PA00X+074716Y+006400X0200Y         S0      
327P3V3_AUX         PC105 -1          A01X+075100Y+003450X0400Y0500R180 S1      
327P3V3_AUX         PC106 -1          A01X+075100Y+004300X0400Y0500R180 S1      
327P3V3_AUX         PC107 -1          A01X+075100Y+005150X0400Y0500R180 S1      
327P3V3_AUX         PC108 -1          A01X+075100Y+006000X0400Y0500R180 S1      
327P3V3_AUX         U4    -24         A10X+081992Y+028800X0140Y0590R180 S2      
327P3V3_AUX         C4    -1   M      A10X+081100Y+027608X0198Y0197R090 S2      
317P3V3_AUX         VIA   -    MD0100PA00X+080850Y+027608X0200Y    R270 S0      
317P3V3_AUX         VIA   -    MD0100PA00X+083100Y+027050X0200Y    R270 S0      
327P3V3_AUX         R90   -1          A10X+083100Y+027292X0198Y0197R270 S2      
317P3V3_AUX         VIA   -    MD0100PA00X+085100Y+027052X0200Y         S0      
327P3V3_AUX         R134  -1          A10X+085100Y+027292X0198Y0197R270 S2      
317P3V3_AUX         VIA   -    MD0100PA00X+084600Y+027052X0200Y         S0      
327P3V3_AUX         R133  -1          A10X+084600Y+027292X0198Y0197R270 S2      
317P3V3_AUX         VIA   -    MD0100PA00X+084100Y+027050X0200Y    R270 S0      
327P3V3_AUX         R92   -1          A10X+084100Y+027292X0198Y0197R270 S2      
317P3V3_AUX         VIA   -    MD0100PA00X+085482Y+033092X0200Y         S0      
327P3V3_AUX         R5903 -2          A10X+085200Y+033092X0198Y0197R090 S2      
317P3V3_AUX         VIA   -    MD0100PA00X+080300Y+034650X0200Y         S0      
327P3V3_AUX         R125  -2          A10X+080058Y+034650X0198Y0197R180 S2      
327P3V3_AUX         R129  -2          A10X+080058Y+033000X0198Y0197R180 S2      
327P3V3_AUX         R100  -2          A10X+080058Y+035200X0198Y0197R180 S2      
317P3V3_AUX         VIA   -    MD0100PA00X+088550Y+035292X0200Y    R270 S0      
327P3V3_AUX         U10   -8          A10X+088000Y+033890X0220Y0680     S2      
327P3V3_AUX         C10   -2   M      A10X+088300Y+035292X0198Y0197R090 S2      
317P3V3_AUX         VIA   -    MD0100PA00X+087400Y+035848X0200Y    R270 S0      
327P3V3_AUX         R36   -1          A10X+087400Y+035608X0198Y0197R090 S2      
317P3V3_AUX         VIA   -    MD0100PA00X+080058Y+033800X0200Y         S0      
327P3V3_AUX         R130  -2   M      A10X+080058Y+033500X0198Y0197R180 S2      
327P3V3_AUX         R101  -2          A10X+080058Y+034100X0198Y0197R180 S2      
317P3V3_AUX         VIA   -    MD0100PA00X+080300Y+035700X0200Y         S0      
327P3V3_AUX         R102  -1   M      A10X+080058Y+035700X0198Y0197     S2      
317P3V3_AUX         VIA   -    MD0100PA00X+082350Y+032900X0200Y         S0      
327P3V3_AUX         R20   -1          A10X+082350Y+032658X0198Y0197R090 S2      
317P3V3_AUX         VIA   -    MD0100PA00X+081550Y+032900X0200Y         S0      
327P3V3_AUX         R19   -1          A10X+081550Y+032658X0198Y0197R090 S2      
317P3V3_AUX         VIA   -    MD0100PA00X+081150Y+032900X0200Y         S0      
327P3V3_AUX         R17   -1          A10X+081150Y+032658X0198Y0197R090 S2      
317P3V3_AUX         VIA   -    M      A01X+088000Y+030452X0300Y    R270 S1      
017P3V3_AUX         VIA   -    M      A10X+088000Y+030452X0200Y    R270 S1      
017P3V3_AUX               -    MD0100PA00X+088000Y+030452                       
327P3V3_AUX         R40   -1          A10X+088000Y+030692X0198Y0197R270 S2      
317P3V3_AUX         VIA   -    MD0100PA00X+087500Y+030452X0200Y    R270 S0      
327P3V3_AUX         R39   -1          A10X+087500Y+030692X0198Y0197R270 S2      
317P3V3_AUX         VIA   -    M      A01X+087000Y+030452X0300Y    R270 S1      
017P3V3_AUX         VIA   -    M      A10X+087000Y+030452X0200Y    R270 S1      
017P3V3_AUX               -    MD0100PA00X+087000Y+030452                       
327P3V3_AUX         R38   -1          A10X+087000Y+030692X0198Y0197R270 S2      
317P3V3_AUX         VIA   -    MD0100PA00X+083969Y+032959X0200Y         S0      
327P3V3_AUX         R28   -1          A10X+083758Y+032800X0198Y0197     S2      
317P3V3_AUX         VIA   -    MD0100PA00X+090450Y+029200X0200Y         S0      
327P3V3_AUX         R24   -2          A10X+090450Y+029442X0198Y0197R090 S2      
317P3V3_AUX         VIA   -    MD0100PA00X+094317Y+031088X0200Y         S0      
327P3V3_AUX         R2    -2          A10X+094077Y+031088X0198Y0197R180 S2      
317P3V3_AUX         VIA   -    MD0100PA00X+094700Y+030248X0200Y         S0      
327P3V3_AUX         R74   -1          A10X+094700Y+030008X0198Y0197R090 S2      
317P3V3_AUX         VIA   -    MD0100PA00X+093752Y+030008X0200Y         S0      
327P3V3_AUX         R75   -1          A10X+094000Y+030008X0198Y0197R090 S2      
317P3V3_AUX         VIA   -    MD0100PA00X+092600Y+028348X0200Y         S0      
327P3V3_AUX         R199  -1          A10X+092600Y+028108X0198Y0197R090 S2      
317P3V3_AUX         VIA   -    MD0100PA00X+094388Y+035238X0200Y         S0      
327P3V3_AUX         R1    -2          A10X+094127Y+035238X0198Y0197R180 S2      
317P3V3_AUX         VIA   -    MD0100PA00X+092700Y+035792X0200Y         S0      
327P3V3_AUX         U9    -5          A10X+092374Y+035082X0180Y0520     S2      
327P3V3_AUX         C9    -2   M      A10X+092450Y+035792X0198Y0197R090 S2      
317P3V3_AUX         VIA   -    MD0100PA00X+092000Y+035552X0200Y         S0      
327P3V3_AUX         R34   -1          A10X+092000Y+035792X0198Y0197R270 S2      
317P3V3_AUX         VIA   -    MD0100PA00X+093050Y+031546X0200Y         S0      
327P3V3_AUX         C1    -1   M      A10X+093320Y+031546X0198Y0197R090 S2      
327P3V3_AUX         U1    -8          A10X+093336Y+032260X0140Y0560R180 S2      
317P3V3_AUX         VIA   -    MD0100PA00X+091200Y+033242X0200Y         S0      
327P3V3_AUX         R142  -1          A10X+090950Y+033242X0198Y0197R270 S2      
317P3V3_AUX         VIA   -    MD0100PA00X+091500Y+032242X0200Y    R180 S0      
327P3V3_AUX         U5    -5          A10X+091106Y+031674X0170Y0240     S2      
327P3V3_AUX         C5    -1   M      A10X+091250Y+032242X0198Y0197R270 S2      
317P3V3_AUX         VIA   -    MD0100PA00X+074200Y+034150X0200Y         S0      
327P3V3_AUX         R106  -2          A10X+074492Y+034250X0198Y0197     S2      
327P3V3_AUX         C8    -2   M      A10X+085300Y+035692X0198Y0197R090 S2      
327P3V3_AUX         U8    -5          A10X+085224Y+034982X0180Y0520     S2      
317P3V3_AUX         VIA   -    MD0100PA00X+085050Y+035692X0200Y         S0      
317m0109            VIA   -    M      A01X+119384Y+047125X0200Y         S2      
017m0109            VIA   -    M      A10X+119384Y+047125X0260Y         S2      
017m0109                  -    MD0100PA00X+119384Y+047125                       
327m0109            PR6960-2   M      A01X+119040Y+047125X0280Y0320R270 S1      
327m0109            PR6963-2   M      A01X+119040Y+047825X0280Y0320R270 S1      
327m0109            PR6956-2          A01X+119040Y+048425X0280Y0320R270 S1      
317m0109            VIA   -    MD0100PA00X+117988Y+044844X0200Y         S0      
327m0109            PR1   -1B         A01X+118280Y+045044X0100Y0200R180 S1      
327P52V_HS1_GPO1    R152  -2          A10X+111000Y+014508X0198Y0197R270 S2      
327P52V_HS1_GPO1    R153  -1   M      A10X+111400Y+014508X0198Y0197R090 S2      
317P52V_HS1_GPO1    VIA   -    M      A01X+112124Y+014450X0200Y         S2      
017P52V_HS1_GPO1    VIA   -    M      A10X+112124Y+014450X0260Y         S2      
017P52V_HS1_GPO1          -    MD0100PA00X+112124Y+014450                       
327P52V_HS1_GPO1    PU7   -14         A01X+112124Y+015312X0120Y0330     S1      
327P52V_HS1_GATE2   PQ2   -G          A01X+107616Y+046044X0520Y1220R270 S1      
327P52V_HS1_GATE2   PR12  -2          A01X+106450Y+046044X0280Y0320R180 S1      
317P52V_HS1_GATE2   VIA   -           A01X+106773Y+046035X0200Y         S2      
017P52V_HS1_GATE2   VIA   -           A10X+106773Y+046035X0260Y         S2      
017P52V_HS1_GATE2         -     D0100PA00X+106773Y+046035                       
327RST_SMB_PDB_N    VIA   -    M      A10X+092000Y+032014X0260Y         S2      
327RST_SMB_PDB_N    U9    -2          A10X+092000Y+034118X0180Y0520     S2      
327RST_SMB_PDB_N    R69   -1          A10X+093300Y+028108X0198Y0197R090 S2      
327P52V_HS1_GATE1   PQ1   -G          A01X+107616Y+050794X0520Y1220R270 S1      
327P52V_HS1_GATE1   PR8   -2          A01X+106450Y+050794X0280Y0320R180 S1      
317P52V_HS1_GATE1   VIA   -           A01X+106787Y+050763X0200Y         S2      
017P52V_HS1_GATE1   VIA   -           A10X+106787Y+050763X0260Y         S2      
017P52V_HS1_GATE1         -     D0100PA00X+106787Y+050763                       
327FAN_PWR_EN       R5903 -1          A10X+085200Y+033408X0198Y0197R090 S2      
317FAN_PWR_EN       VIA   -    MD0100PA00X+090900Y+028348X0200Y         S0      
327FAN_PWR_EN       R70   -2          A10X+090900Y+028108X0198Y0197R270 S2      
317FAN_PWR_EN       VIA   -    M      A01X+084850Y+033580X0300Y         S1      
017FAN_PWR_EN       VIA   -    M      A10X+084850Y+033580X0200Y         S1      
017FAN_PWR_EN             -    MD0100PA00X+084850Y+033580                       
327FAN_PWR_EN       U8    -2          A10X+084850Y+034018X0180Y0520     S2      
327P52V_HS1_TEMPP   PU7   -44         A01X+112715Y+018028X0120Y0330     S1      
317P52V_HS1_TEMPP   VIA   -    MD0100PA00X+112592Y+019542X0200Y         S0      
327P52V_HS1_TEMPP   PC560 -1   M      A01X+112592Y+019276X0198Y0197     S1      
317P52V_HS1_TEMPP   VIA   -    M      A01X+111721Y+023174X0200Y         S2      
017P52V_HS1_TEMPP   VIA   -    M      A10X+111721Y+023174X0260Y         S2      
017P52V_HS1_TEMPP         -    MD0100PA00X+111721Y+023174                       
327P52V_HS1_TEMPP   PR6967-1          A01X+111481Y+023174X0180Y0200     S1      
317m0110            VIA   -    M      A01X+116519Y+047125X0200Y         S2      
017m0110            VIA   -    M      A10X+116519Y+047125X0260Y         S2      
017m0110                  -    MD0100PA00X+116519Y+047125                       
327m0110            PR6958-2   M      A01X+116860Y+047125X0280Y0320R090 S1      
327m0110            PR6962-2   M      A01X+116860Y+047825X0280Y0320R090 S1      
327m0110            PR6957-2          A01X+116860Y+048425X0280Y0320R090 S1      
327m0110            PR1   -2B         A01X+117668Y+045044X0100Y0200R180 S1      
317m0110            VIA   -    MD0100PA00X+117988Y+045244X0200Y         S0      
327SMB_BRICK3_SDA   R178  -2          A10X+021608Y+030050X0198Y0197R180 S2      
317SMB_BRICK3_SDA   PU4   -10   D0360PA00X+021594Y+026720X0520Y    R270 S3      
327P52V_1           VIA   -           A01X+118900Y+026600X0300Y         S1      
327P52V_1           VIA   -           A01X+118900Y+024850X0300Y         S1      
327P52V_1           VIA   -           A01X+119050Y+040250X0300Y         S1      
327P52V_1           VIA   -           A01X+119050Y+042000X0300Y         S1      
317P52V_1           VIA   -    MD0100PA00X+117150Y+021400X0200Y         S0      
317P52V_1           VIA   -    MD0100PA00X+117150Y+021100X0200Y         S0      
317P52V_1           VIA   -    MD0100PA00X+117150Y+020800X0200Y         S0      
317P52V_1           VIA   -    MD0100PA00X+117150Y+020500X0200Y         S0      
317P52V_1           VIA   -    MD0100PA00X+117450Y+020500X0200Y         S0      
317P52V_1           VIA   -    MD0100PA00X+117450Y+020800X0200Y         S0      
317P52V_1           VIA   -    MD0100PA00X+117450Y+021100X0200Y         S0      
317P52V_1           VIA   -    MD0100PA00X+117450Y+021400X0200Y         S0      
327P52V_1           R5890 -1          A10X+116760Y+019704X0440Y0540R270 S2      
327P52V_1           VIA   -           A01X+124800Y+045800X0300Y         S1      
327P52V_1           VIA   -           A01X+123000Y+045800X0300Y         S1      
327P52V_1           PR1   -1A         A01X+118860Y+045044X1260Y2700     S1      
327P52V_1           PR315 -1A         A01X+118851Y+030794X1260Y2700     S1      
327P52V_1           FS1   -2          A01X+118310Y+021291X1280Y1350R090 S1      
327P52V_1           PR5   -1          A01X+115500Y+020580X0400Y0630R270 S1      
327P52V_1           PR18  -1          A10X+112774Y+021450X0440Y0540R180 S2      
327P52V_1           PR4   -1          A10X+115550Y+021374X0440Y0540R270 S2      
327P52V_1           PR3   -1          A10X+114050Y+021374X0440Y0540R270 S2      
327P52V_1           PR2   -1          A10X+114800Y+021374X0440Y0540R270 S2      
317P52V_1           VIA   -    MD0100PA00X+119789Y+030989X0200Y         S0      
317P52V_1           VIA   -    MD0100PA00X+120089Y+030989X0200Y         S0      
317P52V_1           VIA   -    MD0100PA00X+120389Y+030989X0200Y         S0      
317P52V_1           VIA   -    MD0100PA00X+119789Y+031289X0200Y         S0      
317P52V_1           VIA   -    MD0100PA00X+120089Y+031289X0200Y         S0      
317P52V_1           VIA   -    MD0100PA00X+120389Y+031289X0200Y         S0      
317P52V_1           VIA   -    MD0100PA00X+119789Y+031589X0200Y         S0      
317P52V_1           VIA   -    MD0100PA00X+120089Y+031589X0200Y         S0      
317P52V_1           VIA   -    MD0100PA00X+120389Y+031589X0200Y         S0      
317P52V_1           VIA   -    MD0100PA00X+119789Y+031889X0200Y         S0      
317P52V_1           VIA   -    MD0100PA00X+120089Y+031889X0200Y         S0      
317P52V_1           VIA   -    MD0100PA00X+120389Y+031889X0200Y         S0      
317P52V_1           VIA   -    MD0100PA00X+120389Y+032189X0200Y         S0      
317P52V_1           VIA   -    MD0100PA00X+120089Y+032189X0200Y         S0      
317P52V_1           VIA   -    MD0100PA00X+119789Y+032189X0200Y         S0      
317P52V_1           VIA   -    MD0100PA00X+119789Y+029489X0200Y         S0      
317P52V_1           VIA   -    MD0100PA00X+120089Y+029489X0200Y         S0      
317P52V_1           VIA   -    MD0100PA00X+120389Y+029489X0200Y         S0      
317P52V_1           VIA   -    MD0100PA00X+119789Y+029789X0200Y         S0      
317P52V_1           VIA   -    MD0100PA00X+120089Y+029789X0200Y         S0      
317P52V_1           VIA   -    MD0100PA00X+120389Y+029789X0200Y         S0      
317P52V_1           VIA   -    MD0100PA00X+119789Y+030089X0200Y         S0      
317P52V_1           VIA   -    MD0100PA00X+120089Y+030089X0200Y         S0      
317P52V_1           VIA   -    MD0100PA00X+120389Y+030089X0200Y         S0      
317P52V_1           VIA   -    MD0100PA00X+119789Y+030389X0200Y         S0      
317P52V_1           VIA   -    MD0100PA00X+120089Y+030389X0200Y         S0      
317P52V_1           VIA   -    MD0100PA00X+120389Y+030389X0200Y         S0      
317P52V_1           VIA   -    MD0100PA00X+119789Y+030689X0200Y         S0      
317P52V_1           VIA   -    MD0100PA00X+120089Y+030689X0200Y         S0      
317P52V_1           VIA   -    MD0100PA00X+120389Y+030689X0200Y         S0      
317P52V_1           VIA   -    MD0100PA00X+120398Y+046139X0200Y         S0      
317P52V_1           VIA   -    MD0100PA00X+120098Y+046139X0200Y         S0      
317P52V_1           VIA   -    MD0100PA00X+119798Y+046139X0200Y         S0      
317P52V_1           VIA   -    MD0100PA00X+120398Y+045839X0200Y         S0      
317P52V_1           VIA   -    MD0100PA00X+120098Y+045839X0200Y         S0      
317P52V_1           VIA   -    MD0100PA00X+119798Y+045839X0200Y         S0      
317P52V_1           VIA   -    MD0100PA00X+120398Y+045539X0200Y         S0      
317P52V_1           VIA   -    MD0100PA00X+120098Y+045539X0200Y         S0      
317P52V_1           VIA   -    MD0100PA00X+119798Y+045539X0200Y         S0      
317P52V_1           VIA   -    MD0100PA00X+120398Y+045239X0200Y         S0      
317P52V_1           VIA   -    MD0100PA00X+120098Y+045239X0200Y         S0      
317P52V_1           VIA   -    MD0100PA00X+119798Y+045239X0200Y         S0      
317P52V_1           VIA   -    MD0100PA00X+120398Y+044939X0200Y         S0      
317P52V_1           VIA   -    MD0100PA00X+120098Y+044939X0200Y         S0      
317P52V_1           VIA   -    MD0100PA00X+119798Y+044939X0200Y         S0      
317P52V_1           VIA   -    MD0100PA00X+120398Y+044639X0200Y         S0      
317P52V_1           VIA   -    MD0100PA00X+120098Y+044639X0200Y         S0      
317P52V_1           VIA   -    MD0100PA00X+119798Y+044639X0200Y         S0      
317P52V_1           VIA   -    MD0100PA00X+120398Y+044339X0200Y         S0      
317P52V_1           VIA   -    MD0100PA00X+120098Y+044339X0200Y         S0      
317P52V_1           VIA   -    MD0100PA00X+119798Y+044339X0200Y         S0      
317P52V_1           VIA   -    MD0100PA00X+120398Y+044039X0200Y         S0      
317P52V_1           VIA   -    MD0100PA00X+120098Y+044039X0200Y         S0      
317P52V_1           VIA   -    MD0100PA00X+119798Y+044039X0200Y         S0      
317P52V_1           VIA   -    MD0100PA00X+120398Y+043739X0200Y         S0      
317P52V_1           VIA   -    MD0100PA00X+120098Y+043739X0200Y         S0      
317P52V_1           VIA   -    MD0100PA00X+119798Y+043739X0200Y         S0      
317P52V_1           VIA   -    MD0100PA00X+120398Y+046439X0200Y         S0      
317P52V_1           VIA   -    MD0100PA00X+120098Y+046439X0200Y         S0      
317P52V_1           VIA   -    MD0100PA00X+119798Y+046439X0200Y         S0      
317P52V_1           J5    -P1_1MD0402PA00X+125602Y+035193X0602Y         S3      
317P52V_1           J5    -P1_2MD0402PA00X+124602Y+035193X0602Y         S3      
317P52V_1           J5    -P1_3MD0402PA00X+123602Y+035193X0602Y         S3      
317P52V_1           J5    -P1_5MD0402PA00X+125602Y+034193X0602Y         S3      
317P52V_1           J5    -P1_6MD0402PA00X+124602Y+034193X0602Y         S3      
317P52V_1           J5    -P1_7MD0402PA00X+123602Y+034193X0602Y         S3      
317P52V_1           J5    -P1_4MD0402PA00X+122602Y+035193X0602Y         S3      
317P52V_1           J5    -P1_8MD0402PA00X+122602Y+034193X0602Y         S3      
317P52V_1           J5    -P2_1MD0402PA00X+125602Y+031693X0602Y         S3      
317P52V_1           J5    -P2_2MD0402PA00X+124602Y+031693X0602Y         S3      
317P52V_1           J5    -P2_3MD0402PA00X+123602Y+031693X0602Y         S3      
317P52V_1           J5    -P2_5MD0402PA00X+125602Y+030693X0602Y         S3      
317P52V_1           J5    -P2_6MD0402PA00X+124602Y+030693X0602Y         S3      
317P52V_1           J5    -P2_7MD0402PA00X+123602Y+030693X0602Y         S3      
317P52V_1           J5    -P2_4MD0402PA00X+122602Y+031693X0602Y         S3      
317P52V_1           J5    -P2_8MD0402PA00X+122602Y+030693X0602Y         S3      
327m0111            PR318 -1   M      A10X+071988Y+030042X0180Y0200R090 S2      
317m0111            VIA   -    MD0100PA00X+072400Y+029450X0200Y         S0      
327m0111            PR323 -1   M      A10X+072400Y+030042X0198Y0197R270 S2      
317m0111            PU6   -14   D0360PA00X+071988Y+026720X0520Y    R270 S3      
317m0111            VIA   -    MD0100PA00X+071610Y+025599X0200Y         S0      
327m0111            PR322 -2          A10X+025150Y+030358X0198Y0197R270 S2      
327m0112            R144  -2          A01X+110008Y+014750X0198Y0197     S1      
327m0112            PU7   -10         A01X+111652Y+015981X0120Y0330R270 S1      
327m0112            VIA   -    M      A01X+110650Y+015500X0300Y         S1      
327m0113            R177  -2          A10X+022382Y+045858X0198Y0197R270 S2      
317m0113            PU4   -2    D0630PA00X+022382Y+047720X0930Y    R270 S3      
327m0114            PR79  -1          A10X+020807Y+030042X0198Y0197R270 S2      
317m0114            PU4   -9    D0360PA00X+020807Y+026720X0520Y    R270 S3      
327P52V_HS1_GPO2    R150  -2          A01X+110850Y+014208X0198Y0197R090 S1      
327P52V_HS1_GPO2    R151  -1   M      A01X+111250Y+014208X0198Y0197R270 S1      
327P52V_HS1_GPO2    VIA   -    M      A01X+111800Y+014600X0300Y         S1      
327P52V_HS1_GPO2    PU7   -13         A01X+111927Y+015312X0120Y0330     S1      
317m0115            VIA   -    MD0100PA00X+112608Y+013597X0200Y         S0      
327m0115            VIA   -    M      A01X+112715Y+014757X0300Y         S1      
327m0115            R148  -2          A01X+112344Y+013200X0440Y0540R270 S1      
327m0115            R149  -1   M      A01X+112608Y+013846X0198Y0197R180 S1      
327m0115            PU7   -17         A01X+112715Y+015312X0120Y0330     S1      
327m0115            PR6935-1   M      A01X+112659Y+014256X0198Y0197     S1      
327m0115            C55   -2   M      A10X+058950Y+045208X0198Y0197R270 S2      
317m0115            VIA   -    MD0100PA00X+070440Y+035860X0200Y         S0      
327m0115            U23   -G          A10X+058394Y+045174X0320Y0360R090 S2      
317m0116            JP2   -1    D0460PA00X+101100Y+009800X0660Y0660R090 S3      
327m0116            PR92  -2          A01X+101942Y+009800X0198Y0197R180 S1      
327m0117            R179  -2          A10X+022458Y+030050X0198Y0197R180 S2      
317m0117            PU4   -11   D0360PA00X+022382Y+026720X0520Y    R270 S3      
327SMB_BRICK3_SCL   R180  -2          A10X+023358Y+030050X0198Y0197R180 S2      
317SMB_BRICK3_SCL   PU4   -12   D0360PA00X+023169Y+026720X0520Y    R270 S3      
327m0118            PR313 -2          A01X+101942Y+011800X0198Y0197R180 S1      
317m0118            JP2   -3    D0460PA00X+101100Y+011800X0660Y    R090 S3      
327m0119            VIA   -    M      A10X+053500Y+029590X0260Y         S2      
327m0119            R162  -2          A10X+053692Y+031050X0198Y0197     S2      
327m0119            C53   -1   M      A10X+053692Y+030550X0198Y0197R180 S2      
327m0119            R165  -1   M      A10X+053692Y+030050X0198Y0197R180 S2      
327m0119            U4    -5          A10X+083016Y+031100X0140Y0590R180 S2      
327P52V_HS1_GATE3   PR13  -2          A01X+106450Y+041294X0280Y0320R180 S1      
327P52V_HS1_GATE3   PQ3   -G          A01X+107616Y+041294X0520Y1220R270 S1      
317P52V_HS1_GATE3   VIA   -           A01X+106753Y+041294X0200Y         S2      
017P52V_HS1_GATE3   VIA   -           A10X+106753Y+041294X0260Y         S2      
017P52V_HS1_GATE3         -     D0100PA00X+106753Y+041294                       
317P52V_HS1_ADR1    VIA   -    M      A01X+104936Y+014390X0200Y         S2      
017P52V_HS1_ADR1    VIA   -    M      A10X+104936Y+014390X0260Y         S2      
017P52V_HS1_ADR1          -    MD0100PA00X+104936Y+014390                       
327P52V_HS1_ADR1    PU1   -17         A01X+104741Y+014938X0110Y0300     S1      
327P52V_HS1_ADR1    R5906 -2   M      A10X+104508Y+015100X0198Y0197R180 S2      
327P52V_HS1_ADR1    R159  -1   M      A10X+107000Y+018592X0198Y0197R270 S2      
327P52V_HS1_ADR1    R5908 -1   M      A10X+107350Y+018592X0198Y0197R270 S2      
327P52V_HS1_ADR1    R157  -2   M      A10X+110358Y+018350X0198Y0197R180 S2      
317P52V_HS1_ADR1    VIA   -    MD0100PA00X+111110Y+016375X0200Y         S0      
327P52V_HS1_ADR1    PU7   -8          A01X+111652Y+016375X0120Y0330R270 S1      
327m0120            C14   -1          A10X+093300Y+028792X0198Y0197R270 S2      
327m0120            R69   -2   M      A10X+093300Y+027792X0198Y0197R090 S2      
327m0120            VIA   -    M      A10X+093009Y+027299X0260Y         S2      
317m0120            J1    -B1   D0402PA00X+083256Y+013941X0602Y    R270 S3      
317m0121            VIA   -    MD0100PA00X+115278Y+016572X0200Y         S0      
327m0121            PU7   -30         A01X+114762Y+016572X0120Y0330R270 S1      
317m0121            VIA   -    M      A01X+115820Y+013770X0200Y         S2      
017m0121            VIA   -    M      A10X+115820Y+013770X0260Y         S2      
017m0121                  -    MD0100PA00X+115820Y+013770                       
327m0121            PR32  -1          A01X+115259Y+013168X0440Y0540R270 S1      
317m0122            VIA   -    M      A01X+113012Y+013594X0200Y         S2      
017m0122            VIA   -    M      A10X+113012Y+013594X0260Y         S2      
017m0122                  -    MD0100PA00X+113012Y+013594                       
327m0122            PR17  -2          A01X+113294Y+013200X0440Y0540R270 S1      
327m0122            PR6932-1   M      A01X+113012Y+013846X0198Y0197     S1      
327m0122            PU7   -18         A01X+112912Y+015312X0120Y0330     S1      
327m0122            PR6935-2   M      A01X+112974Y+014256X0198Y0197     S1      
327m0123            PU7   -46         A01X+112321Y+018028X0120Y0330     S1      
317m0123            VIA   -    MD0100PA00X+111900Y+018950X0200Y         S0      
327m0123            PU1   -11         A01X+103560Y+014938X0110Y0300     S1      
317m0123            VIA   -    M      A01X+103450Y+014500X0200Y         S2      
017m0123            VIA   -    M      A10X+103450Y+014500X0260Y         S2      
017m0123                  -    MD0100PA00X+103450Y+014500                       
327m0123            PR10  -1   M      A10X+114058Y+019650X0198Y0197     S2      
327m0123            PR3   -2          A10X+114050Y+020626X0440Y0540R270 S2      
327m0123            PC2   -1   M      A10X+114058Y+020050X0198Y0197     S2      
317P52V_HS          VIA   -    MD0100PA00X+108750Y+020100X0200Y         S0      
317P52V_HS          VIA   -    MD0100PA00X+108750Y+019800X0200Y         S0      
327P52V_HS          PR19  -1          A01X+109126Y+019950X0440Y0540R180 S1      
327P52V_HS          PR23  -1          A01X+102081Y+019927X0440Y0540R180 S1      
327P52V_HS          R5873 -3          A10X+015063Y+041450X0160Y0440R270 S2      
317P52V_HS          VIA   -    MD0100PA00X+016380Y+042370X0200Y         S0      
317P52V_HS          VIA   -    MD0100PA00X+016380Y+042670X0200Y         S0      
317P52V_HS          VIA   -    MD0100PA00X+015680Y+042660X0200Y         S0      
317P52V_HS          VIA   -    MD0100PA00X+016030Y+042660X0200Y         S0      
317P52V_HS          VIA   -    MD0100PA00X+015680Y+042360X0200Y         S0      
317P52V_HS          VIA   -    MD0100PA00X+016030Y+042360X0200Y         S0      
317P52V_HS          VIA   -    MD0100PA00X+016400Y+040860X0200Y         S0      
317P52V_HS          VIA   -    MD0100PA00X+016400Y+041160X0200Y         S0      
317P52V_HS          VIA   -    MD0100PA00X+016400Y+042060X0200Y         S0      
317P52V_HS          VIA   -    MD0100PA00X+016400Y+041760X0200Y         S0      
317P52V_HS          VIA   -    MD0100PA00X+016400Y+041460X0200Y         S0      
327P52V_HS          PU1   -1          A01X+102507Y+017359X0110Y0280R270 S1      
327P52V_HS          PR25  -1          A01X+102081Y+018877X0440Y0540R180 S1      
317P52V_HS          VIA   -    MD0100PA00X+101661Y+019777X0200Y         S0      
317P52V_HS          VIA   -    M      A01X+101661Y+019027X0200Y         S2      
017P52V_HS          VIA   -    M      A10X+101661Y+019027X0260Y         S2      
017P52V_HS                -    MD0100PA00X+101661Y+019027                       
317P52V_HS          VIA   -    MD0100PA00X+101661Y+018727X0200Y         S0      
327P52V_HS          PC82  -2          A10X+108044Y+039994X0280Y0320R090 S2      
327P52V_HS          PC553 -2          A10X+108044Y+039250X0280Y0320R090 S2      
327P52V_HS          C36   -1          A10X+095200Y+038180X0460Y0620R270 S2      
327P52V_HS          C34   -1          A10X+094250Y+038180X0460Y0620R270 S2      
327P52V_HS          C28   -1          A10X+091350Y+038180X0460Y0620R270 S2      
327P52V_HS          C30   -1          A10X+092350Y+038180X0460Y0620R270 S2      
327P52V_HS          C32   -1          A10X+093300Y+038180X0460Y0620R270 S2      
327P52V_HS          C38   -1          A10X+087550Y+038180X0460Y0620R270 S2      
327P52V_HS          C24   -1          A10X+089450Y+038180X0460Y0620R270 S2      
327P52V_HS          C22   -1          A10X+088500Y+038180X0460Y0620R270 S2      
327P52V_HS          C26   -1          A10X+090400Y+038180X0460Y0620R270 S2      
327P52V_HS          C42   -1          A10X+085650Y+038180X0460Y0620R270 S2      
327P52V_HS          C44   -1          A10X+084700Y+038180X0460Y0620R270 S2      
327P52V_HS          C40   -1          A10X+086600Y+038180X0460Y0620R270 S2      
327P52V_HS          PC565 -2          A10X+108044Y+034394X0280Y0320R090 S2      
327P52V_HS          PC564 -2          A10X+108044Y+035244X0280Y0320R090 S2      
327P52V_HS          PD8   -C          A01X+107761Y+054550X0990Y1300     S1      
327P52V_HS          L3    -1          A01X+090420Y+051307X1160Y1970R180 S1      
327P52V_HS          PQ1   -S          A01X+107616Y+048794X0520Y1220R270 S1      
327P52V_HS          PQ2   -S          A01X+107616Y+044044X0520Y1220R270 S1      
327P52V_HS          L1    -1          A01X+086392Y+042457X1160Y1970R090 S1      
327P52V_HS          L5    -1          A01X+080732Y+042457X1160Y1970R090 S1      
327P52V_HS          PQ3   -S          A01X+107616Y+039294X0520Y1220R270 S1      
327P52V_HS          C45   -1          A01X+095200Y+038180X0460Y0620R090 S1      
327P52V_HS          C43   -1          A01X+094250Y+038180X0460Y0620R090 S1      
327P52V_HS          C39   -1          A01X+092350Y+038180X0460Y0620R090 S1      
327P52V_HS          C37   -1          A01X+091400Y+038180X0460Y0620R090 S1      
327P52V_HS          C35   -1          A01X+090450Y+038180X0460Y0620R090 S1      
327P52V_HS          C41   -1          A01X+093300Y+038180X0460Y0620R090 S1      
327P52V_HS          C33   -1          A01X+089500Y+038180X0460Y0620R090 S1      
327P52V_HS          C31   -1          A01X+088550Y+038180X0460Y0620R090 S1      
327P52V_HS          C29   -1          A01X+087600Y+038180X0460Y0620R090 S1      
327P52V_HS          C25   -1          A01X+085800Y+038180X0460Y0620R090 S1      
327P52V_HS          C27   -1          A01X+086700Y+038180X0460Y0620R090 S1      
327P52V_HS          C23   -1          A01X+084900Y+038180X0460Y0620R090 S1      
327P52V_HS          R55   -1          A01X+084000Y+038230X0400Y0630R270 S1      
327P52V_HS          PQ4   -S          A01X+107616Y+034544X0520Y1220R270 S1      
327P52V_HS          PQ5   -S          A01X+107616Y+029794X0520Y1220R270 S1      
327P52V_HS          PQ6   -S          A01X+107616Y+025044X0520Y1220R270 S1      
317P52V_HS          VIA   -    MD0100PA00X+116020Y+017598X0200Y         S0      
317P52V_HS          VIA   -    MD0100PA00X+116270Y+017596X0200Y         S0      
327P52V_HS          PC559 -1          A01X+116120Y+017180X0460Y0620R090 S1      
327P52V_HS          PU7   -31         A01X+114762Y+016768X0120Y0330R270 S1      
327P52V_HS          R148  -1          A01X+112344Y+012452X0440Y0540R270 S1      
327P52V_HS          PR17  -1          A01X+113294Y+012452X0440Y0540R270 S1      
317P52V_HS          VIA   -    MD0100PA00X+113150Y+012082X0200Y         S0      
317P52V_HS          VIA   -    MD0100PA00X+113450Y+012082X0200Y         S0      
317P52V_HS          VIA   -    MD0100PA00X+112600Y+012082X0200Y         S0      
317P52V_HS          VIA   -    MD0100PA00X+112300Y+012082X0200Y         S0      
327P52V_HS          R5873 -1          A10X+015457Y+041450X1260Y0591R090 S2      
317P52V_HS          VIA   -    MD0100PA00X+015700Y+040850X0200Y         S0      
317P52V_HS          VIA   -    MD0100PA00X+016050Y+040850X0200Y         S0      
317P52V_HS          VIA   -    MD0100PA00X+015700Y+041150X0200Y         S0      
317P52V_HS          VIA   -    MD0100PA00X+016050Y+041150X0200Y         S0      
317P52V_HS          VIA   -    MD0100PA00X+015700Y+042050X0200Y         S0      
317P52V_HS          VIA   -    MD0100PA00X+016050Y+042050X0200Y         S0      
317P52V_HS          VIA   -    MD0100PA00X+015700Y+041750X0200Y         S0      
317P52V_HS          VIA   -    MD0100PA00X+016050Y+041750X0200Y         S0      
317P52V_HS          VIA   -    MD0100PA00X+016050Y+041450X0200Y         S0      
317P52V_HS          VIA   -    MD0100PA00X+015700Y+041450X0200Y         S0      
327P52V_HS          R398  -1          A10X+056300Y+044576X0440Y0540R090 S2      
317P52V_HS          VIA   -    MD0100PA00X+056450Y+044200X0200Y         S0      
317P52V_HS          VIA   -    MD0100PA00X+056200Y+044200X0200Y         S0      
317P52V_HS          VIA   -    MD0100PA00X+091178Y+051618X0200Y    R180 S0      
317P52V_HS          VIA   -    MD0100PA00X+091478Y+051618X0200Y    R180 S0      
317P52V_HS          VIA   -    MD0100PA00X+091754Y+051618X0200Y    R180 S0      
317P52V_HS          VIA   -    MD0100PA00X+092060Y+051901X0200Y    R180 S0      
317P52V_HS          VIA   -    MD0100PA00X+092360Y+051901X0200Y    R180 S0      
317P52V_HS          VIA   -    MD0100PA00X+091183Y+051901X0200Y    R180 S0      
317P52V_HS          VIA   -    MD0100PA00X+091483Y+051901X0200Y    R180 S0      
317P52V_HS          VIA   -    MD0100PA00X+091760Y+051901X0200Y    R180 S0      
317P52V_HS          VIA   -    MD0100PA00X+092354Y+051618X0200Y    R180 S0      
317P52V_HS          VIA   -    MD0100PA00X+092054Y+051618X0200Y    R180 S0      
317P52V_HS          VIA   -    MD0100PA00X+091178Y+051318X0200Y    R180 S0      
317P52V_HS          VIA   -    MD0100PA00X+091478Y+050418X0200Y    R180 S0      
317P52V_HS          VIA   -    MD0100PA00X+091478Y+050118X0200Y    R180 S0      
317P52V_HS          VIA   -    MD0100PA00X+091478Y+051018X0200Y    R180 S0      
317P52V_HS          VIA   -    MD0100PA00X+091478Y+050718X0200Y    R180 S0      
317P52V_HS          VIA   -    MD0100PA00X+091478Y+051318X0200Y    R180 S0      
317P52V_HS          VIA   -    MD0100PA00X+091754Y+051318X0200Y    R180 S0      
317P52V_HS          VIA   -    MD0100PA00X+091754Y+050718X0200Y    R180 S0      
317P52V_HS          VIA   -    MD0100PA00X+091754Y+051018X0200Y    R180 S0      
317P52V_HS          VIA   -    MD0100PA00X+091754Y+050118X0200Y    R180 S0      
317P52V_HS          VIA   -    MD0100PA00X+091754Y+050418X0200Y    R180 S0      
317P52V_HS          VIA   -    MD0100PA00X+091760Y+049846X0200Y    R180 S0      
317P52V_HS          VIA   -    MD0100PA00X+091483Y+049846X0200Y    R180 S0      
317P52V_HS          VIA   -    MD0100PA00X+091183Y+049846X0200Y    R180 S0      
317P52V_HS          VIA   -    MD0100PA00X+092354Y+051318X0200Y    R180 S0      
317P52V_HS          VIA   -    MD0100PA00X+092054Y+051318X0200Y    R180 S0      
317P52V_HS          VIA   -    MD0100PA00X+092054Y+050718X0200Y    R180 S0      
317P52V_HS          VIA   -    MD0100PA00X+092354Y+050718X0200Y    R180 S0      
317P52V_HS          VIA   -    MD0100PA00X+092054Y+051018X0200Y    R180 S0      
317P52V_HS          VIA   -    MD0100PA00X+092354Y+051018X0200Y    R180 S0      
317P52V_HS          VIA   -    MD0100PA00X+092354Y+050118X0200Y    R180 S0      
317P52V_HS          VIA   -    MD0100PA00X+092054Y+050118X0200Y    R180 S0      
317P52V_HS          VIA   -    MD0100PA00X+092354Y+050418X0200Y    R180 S0      
317P52V_HS          VIA   -    MD0100PA00X+092054Y+050418X0200Y    R180 S0      
317P52V_HS          VIA   -    MD0100PA00X+092060Y+049846X0200Y    R180 S0      
317P52V_HS          VIA   -    MD0100PA00X+092360Y+049846X0200Y    R180 S0      
317P52V_HS          VIA   -    MD0100PA00X+091178Y+050418X0200Y    R180 S0      
317P52V_HS          VIA   -    MD0100PA00X+091178Y+050118X0200Y    R180 S0      
317P52V_HS          VIA   -    MD0100PA00X+091178Y+051018X0200Y    R180 S0      
317P52V_HS          VIA   -    MD0100PA00X+091178Y+050718X0200Y    R180 S0      
317P52V_HS          VIA   -    MD0100PA00X+095311Y+038588X0200Y    R090 S0      
317P52V_HS          VIA   -    MD0100PA00X+095011Y+038588X0200Y    R090 S0      
317P52V_HS          VIA   -    MD0100PA00X+093432Y+038577X0200Y    R090 S0      
317P52V_HS          VIA   -    MD0100PA00X+093132Y+038577X0200Y    R090 S0      
317P52V_HS          VIA   -    MD0100PA00X+094125Y+038588X0200Y    R090 S0      
317P52V_HS          VIA   -    MD0100PA00X+094425Y+038588X0200Y    R090 S0      
317P52V_HS          VIA   -    MD0100PA00X+091552Y+038588X0200Y    R090 S0      
317P52V_HS          VIA   -    MD0100PA00X+092545Y+038577X0200Y    R090 S0      
317P52V_HS          VIA   -    MD0100PA00X+092245Y+038577X0200Y    R090 S0      
317P52V_HS          VIA   -    MD0100PA00X+090366Y+038588X0200Y    R090 S0      
317P52V_HS          VIA   -    MD0100PA00X+090666Y+038588X0200Y    R090 S0      
317P52V_HS          VIA   -    MD0100PA00X+091252Y+038588X0200Y    R090 S0      
317P52V_HS          VIA   -    MD0100PA00X+088723Y+038577X0200Y    R090 S0      
317P52V_HS          VIA   -    MD0100PA00X+088423Y+038577X0200Y    R090 S0      
317P52V_HS          VIA   -    MD0100PA00X+086854Y+038577X0200Y    R090 S0      
317P52V_HS          VIA   -    MD0100PA00X+087740Y+038577X0200Y    R090 S0      
317P52V_HS          VIA   -    MD0100PA00X+087440Y+038577X0200Y    R090 S0      
317P52V_HS          VIA   -    MD0100PA00X+089609Y+038577X0200Y    R090 S0      
317P52V_HS          VIA   -    MD0100PA00X+089309Y+038577X0200Y    R090 S0      
317P52V_HS          VIA   -    MD0100PA00X+086554Y+038577X0200Y    R090 S0      
317P52V_HS          VIA   -    MD0100PA00X+085625Y+038588X0200Y    R090 S0      
317P52V_HS          VIA   -    MD0100PA00X+085925Y+038588X0200Y    R090 S0      
317P52V_HS          VIA   -    MD0100PA00X+084739Y+038588X0200Y    R090 S0      
317P52V_HS          VIA   -    MD0100PA00X+085039Y+038588X0200Y    R090 S0      
317P52V_HS          VIA   -    MD0100PA00X+086234Y+041692X0200Y    R090 S0      
317P52V_HS          VIA   -    MD0100PA00X+086534Y+041692X0200Y    R090 S0      
317P52V_HS          VIA   -    MD0100PA00X+085634Y+041692X0200Y    R090 S0      
317P52V_HS          VIA   -    MD0100PA00X+085934Y+041692X0200Y    R090 S0      
317P52V_HS          VIA   -    MD0100PA00X+085362Y+040510X0200Y    R090 S0      
317P52V_HS          VIA   -    MD0100PA00X+085362Y+040810X0200Y    R090 S0      
317P52V_HS          VIA   -    MD0100PA00X+085934Y+040815X0200Y    R090 S0      
317P52V_HS          VIA   -    MD0100PA00X+085934Y+040515X0200Y    R090 S0      
317P52V_HS          VIA   -    MD0100PA00X+085634Y+040815X0200Y    R090 S0      
317P52V_HS          VIA   -    MD0100PA00X+085634Y+040515X0200Y    R090 S0      
317P52V_HS          VIA   -    MD0100PA00X+086534Y+040515X0200Y    R090 S0      
317P52V_HS          VIA   -    MD0100PA00X+086534Y+040815X0200Y    R090 S0      
317P52V_HS          VIA   -    MD0100PA00X+086234Y+040515X0200Y    R090 S0      
317P52V_HS          VIA   -    MD0100PA00X+086234Y+040815X0200Y    R090 S0      
317P52V_HS          VIA   -    MD0100PA00X+086834Y+040815X0200Y    R090 S0      
317P52V_HS          VIA   -    MD0100PA00X+086834Y+040515X0200Y    R090 S0      
317P52V_HS          VIA   -    MD0100PA00X+087134Y+040815X0200Y    R090 S0      
317P52V_HS          VIA   -    MD0100PA00X+087134Y+040515X0200Y    R090 S0      
317P52V_HS          VIA   -    MD0100PA00X+081432Y+041115X0200Y    R090 S0      
317P52V_HS          VIA   -    MD0100PA00X+081715Y+041110X0200Y    R090 S0      
317P52V_HS          VIA   -    MD0100PA00X+081715Y+041386X0200Y    R090 S0      
317P52V_HS          VIA   -    MD0100PA00X+081432Y+041392X0200Y    R090 S0      
317P52V_HS          VIA   -    MD0100PA00X+081715Y+041686X0200Y    R090 S0      
317P52V_HS          VIA   -    MD0100PA00X+081432Y+041692X0200Y    R090 S0      
317P52V_HS          VIA   -    MD0100PA00X+081432Y+040815X0200Y    R090 S0      
317P52V_HS          VIA   -    MD0100PA00X+081432Y+040515X0200Y    R090 S0      
317P52V_HS          VIA   -    MD0100PA00X+081715Y+040510X0200Y    R090 S0      
317P52V_HS          VIA   -    MD0100PA00X+081715Y+040810X0200Y    R090 S0      
317P52V_HS          VIA   -    MD0100PA00X+079660Y+041686X0200Y    R090 S0      
317P52V_HS          VIA   -    MD0100PA00X+079660Y+041386X0200Y    R090 S0      
317P52V_HS          VIA   -    MD0100PA00X+079660Y+041110X0200Y    R090 S0      
317P52V_HS          VIA   -    MD0100PA00X+080232Y+041115X0200Y    R090 S0      
317P52V_HS          VIA   -    MD0100PA00X+079932Y+041115X0200Y    R090 S0      
317P52V_HS          VIA   -    MD0100PA00X+080832Y+041115X0200Y    R090 S0      
317P52V_HS          VIA   -    MD0100PA00X+080532Y+041115X0200Y    R090 S0      
317P52V_HS          VIA   -    MD0100PA00X+081132Y+041115X0200Y    R090 S0      
317P52V_HS          VIA   -    MD0100PA00X+081132Y+041392X0200Y    R090 S0      
317P52V_HS          VIA   -    MD0100PA00X+080532Y+041392X0200Y    R090 S0      
317P52V_HS          VIA   -    MD0100PA00X+080832Y+041392X0200Y    R090 S0      
317P52V_HS          VIA   -    MD0100PA00X+079932Y+041392X0200Y    R090 S0      
317P52V_HS          VIA   -    MD0100PA00X+080232Y+041392X0200Y    R090 S0      
317P52V_HS          VIA   -    MD0100PA00X+081132Y+041692X0200Y    R090 S0      
317P52V_HS          VIA   -    MD0100PA00X+080532Y+041692X0200Y    R090 S0      
317P52V_HS          VIA   -    MD0100PA00X+080832Y+041692X0200Y    R090 S0      
317P52V_HS          VIA   -    MD0100PA00X+079932Y+041692X0200Y    R090 S0      
317P52V_HS          VIA   -    MD0100PA00X+080232Y+041692X0200Y    R090 S0      
317P52V_HS          VIA   -    MD0100PA00X+079660Y+040510X0200Y    R090 S0      
317P52V_HS          VIA   -    MD0100PA00X+079660Y+040810X0200Y    R090 S0      
317P52V_HS          VIA   -    MD0100PA00X+080232Y+040815X0200Y    R090 S0      
317P52V_HS          VIA   -    MD0100PA00X+080232Y+040515X0200Y    R090 S0      
317P52V_HS          VIA   -    MD0100PA00X+079932Y+040815X0200Y    R090 S0      
317P52V_HS          VIA   -    MD0100PA00X+079932Y+040515X0200Y    R090 S0      
317P52V_HS          VIA   -    MD0100PA00X+080832Y+040515X0200Y    R090 S0      
317P52V_HS          VIA   -    MD0100PA00X+080832Y+040815X0200Y    R090 S0      
317P52V_HS          VIA   -    MD0100PA00X+080532Y+040515X0200Y    R090 S0      
317P52V_HS          VIA   -    MD0100PA00X+080532Y+040815X0200Y    R090 S0      
317P52V_HS          VIA   -    MD0100PA00X+081132Y+040815X0200Y    R090 S0      
317P52V_HS          VIA   -    MD0100PA00X+081132Y+040515X0200Y    R090 S0      
317P52V_HS          VIA   -    MD0100PA00X+087417Y+041110X0200Y    R090 S0      
317P52V_HS          VIA   -    MD0100PA00X+087417Y+041386X0200Y    R090 S0      
317P52V_HS          VIA   -    MD0100PA00X+087417Y+041686X0200Y    R090 S0      
317P52V_HS          VIA   -    MD0100PA00X+087417Y+040510X0200Y    R090 S0      
317P52V_HS          VIA   -    MD0100PA00X+087417Y+040810X0200Y    R090 S0      
317P52V_HS          VIA   -    MD0100PA00X+085362Y+041686X0200Y    R090 S0      
317P52V_HS          VIA   -    MD0100PA00X+085362Y+041386X0200Y    R090 S0      
317P52V_HS          VIA   -    MD0100PA00X+085362Y+041110X0200Y    R090 S0      
317P52V_HS          VIA   -    MD0100PA00X+085934Y+041115X0200Y    R090 S0      
317P52V_HS          VIA   -    MD0100PA00X+085634Y+041115X0200Y    R090 S0      
317P52V_HS          VIA   -    MD0100PA00X+086534Y+041115X0200Y    R090 S0      
317P52V_HS          VIA   -    MD0100PA00X+086234Y+041115X0200Y    R090 S0      
317P52V_HS          VIA   -    MD0100PA00X+086834Y+041115X0200Y    R090 S0      
317P52V_HS          VIA   -    MD0100PA00X+087134Y+041115X0200Y    R090 S0      
317P52V_HS          VIA   -    MD0100PA00X+087134Y+041392X0200Y    R090 S0      
317P52V_HS          VIA   -    MD0100PA00X+086834Y+041392X0200Y    R090 S0      
317P52V_HS          VIA   -    MD0100PA00X+086234Y+041392X0200Y    R090 S0      
317P52V_HS          VIA   -    MD0100PA00X+086534Y+041392X0200Y    R090 S0      
317P52V_HS          VIA   -    MD0100PA00X+085634Y+041392X0200Y    R090 S0      
317P52V_HS          VIA   -    MD0100PA00X+085934Y+041392X0200Y    R090 S0      
317P52V_HS          VIA   -    MD0100PA00X+087134Y+041692X0200Y    R090 S0      
317P52V_HS          VIA   -    MD0100PA00X+086834Y+041692X0200Y    R090 S0      
317P52V_HS          VIA   -    M      A01X+084900Y+039900X0300Y         S1      
017P52V_HS          VIA   -    M      A10X+084900Y+039900X0200Y         S1      
017P52V_HS                -    MD0100PA00X+084900Y+039900                       
317P52V_HS          VIA   -    MD0100PA00X+106950Y+055300X0200Y    R090 S0      
317P52V_HS          VIA   -    M      A01X+106650Y+055300X0200Y    R090 S2      
017P52V_HS          VIA   -    M      A10X+106650Y+055300X0260Y    R090 S2      
017P52V_HS                -    MD0100PA00X+106650Y+055300                       
317P52V_HS          VIA   -    MD0100PA00X+106650Y+055000X0200Y    R090 S0      
317P52V_HS          VIA   -    MD0100PA00X+106650Y+054700X0200Y    R090 S0      
317P52V_HS          VIA   -    MD0100PA00X+106950Y+055000X0200Y    R090 S0      
317P52V_HS          VIA   -    MD0100PA00X+106950Y+054700X0200Y    R090 S0      
317P52V_HS          VIA   -    MD0100PA00X+106950Y+053800X0200Y    R090 S0      
317P52V_HS          VIA   -    MD0100PA00X+106950Y+054400X0200Y    R090 S0      
317P52V_HS          VIA   -    MD0100PA00X+106650Y+054400X0200Y    R090 S0      
317P52V_HS          VIA   -    MD0100PA00X+106950Y+054100X0200Y    R090 S0      
317P52V_HS          VIA   -    MD0100PA00X+106650Y+054100X0200Y    R090 S0      
317P52V_HS          VIA   -    M      A01X+106650Y+053800X0200Y    R090 S2      
017P52V_HS          VIA   -    M      A10X+106650Y+053800X0260Y    R090 S2      
017P52V_HS                -    MD0100PA00X+106650Y+053800                       
317P52V_HS          VIA   -    MD0100PA00X+107200Y+049550X0200Y         S0      
317P52V_HS          VIA   -    MD0100PA00X+107200Y+049250X0200Y         S0      
317P52V_HS          VIA   -    MD0100PA00X+107200Y+048350X0200Y         S0      
317P52V_HS          VIA   -    MD0100PA00X+107200Y+048050X0200Y         S0      
317P52V_HS          VIA   -    MD0100PA00X+106000Y+048650X0200Y         S0      
317P52V_HS          VIA   -    MD0100PA00X+106300Y+048650X0200Y         S0      
317P52V_HS          VIA   -    MD0100PA00X+106600Y+048650X0200Y         S0      
317P52V_HS          VIA   -    MD0100PA00X+106000Y+048950X0200Y         S0      
317P52V_HS          VIA   -    MD0100PA00X+106300Y+048950X0200Y         S0      
317P52V_HS          VIA   -    MD0100PA00X+106600Y+048950X0200Y         S0      
317P52V_HS          VIA   -    MD0100PA00X+106600Y+048350X0200Y         S0      
317P52V_HS          VIA   -    MD0100PA00X+106300Y+048350X0200Y         S0      
317P52V_HS          VIA   -    MD0100PA00X+106000Y+048350X0200Y         S0      
317P52V_HS          VIA   -    MD0100PA00X+106600Y+048050X0200Y         S0      
317P52V_HS          VIA   -    MD0100PA00X+106300Y+048050X0200Y         S0      
317P52V_HS          VIA   -    MD0100PA00X+106000Y+048050X0200Y         S0      
317P52V_HS          VIA   -    MD0100PA00X+106600Y+049550X0200Y         S0      
317P52V_HS          VIA   -    MD0100PA00X+106300Y+049550X0200Y         S0      
317P52V_HS          VIA   -    MD0100PA00X+106000Y+049550X0200Y         S0      
317P52V_HS          VIA   -    MD0100PA00X+106600Y+049250X0200Y         S0      
317P52V_HS          VIA   -    MD0100PA00X+106300Y+049250X0200Y         S0      
317P52V_HS          VIA   -    MD0100PA00X+106000Y+049250X0200Y         S0      
317P52V_HS          VIA   -    MD0100PA00X+106900Y+049550X0200Y         S0      
317P52V_HS          VIA   -    MD0100PA00X+106900Y+049250X0200Y         S0      
317P52V_HS          VIA   -    MD0100PA00X+106900Y+048350X0200Y         S0      
317P52V_HS          VIA   -    MD0100PA00X+106900Y+048050X0200Y         S0      
317P52V_HS          VIA   -    MD0100PA00X+107200Y+044500X0200Y         S0      
317P52V_HS          VIA   -    MD0100PA00X+107200Y+044800X0200Y         S0      
317P52V_HS          VIA   -    MD0100PA00X+106900Y+044500X0200Y         S0      
317P52V_HS          VIA   -    MD0100PA00X+106900Y+044800X0200Y         S0      
317P52V_HS          VIA   -    MD0100PA00X+106000Y+044500X0200Y         S0      
317P52V_HS          VIA   -    MD0100PA00X+106300Y+044500X0200Y         S0      
317P52V_HS          VIA   -    MD0100PA00X+106600Y+044500X0200Y         S0      
317P52V_HS          VIA   -    MD0100PA00X+106000Y+044800X0200Y         S0      
317P52V_HS          VIA   -    MD0100PA00X+106300Y+044800X0200Y         S0      
317P52V_HS          VIA   -    MD0100PA00X+106600Y+044800X0200Y         S0      
317P52V_HS          VIA   -    MD0100PA00X+107200Y+043600X0200Y         S0      
317P52V_HS          VIA   -    MD0100PA00X+107200Y+043300X0200Y         S0      
317P52V_HS          VIA   -    MD0100PA00X+106900Y+043600X0200Y         S0      
317P52V_HS          VIA   -    MD0100PA00X+106000Y+043600X0200Y         S0      
317P52V_HS          VIA   -    MD0100PA00X+106300Y+043600X0200Y         S0      
317P52V_HS          VIA   -    MD0100PA00X+106600Y+043600X0200Y         S0      
317P52V_HS          VIA   -    MD0100PA00X+106600Y+044200X0200Y         S0      
317P52V_HS          VIA   -    MD0100PA00X+106300Y+044200X0200Y         S0      
317P52V_HS          VIA   -    MD0100PA00X+106000Y+044200X0200Y         S0      
317P52V_HS          VIA   -    MD0100PA00X+106600Y+043900X0200Y         S0      
317P52V_HS          VIA   -    MD0100PA00X+106300Y+043900X0200Y         S0      
317P52V_HS          VIA   -    MD0100PA00X+106000Y+043900X0200Y         S0      
317P52V_HS          VIA   -    MD0100PA00X+106900Y+043300X0200Y         S0      
317P52V_HS          VIA   -    MD0100PA00X+106000Y+043300X0200Y         S0      
317P52V_HS          VIA   -    MD0100PA00X+106300Y+043300X0200Y         S0      
317P52V_HS          VIA   -    MD0100PA00X+106600Y+043300X0200Y         S0      
317P52V_HS          VIA   -    MD0100PA00X+107200Y+038550X0200Y         S0      
317P52V_HS          VIA   -    MD0100PA00X+107200Y+038850X0200Y         S0      
317P52V_HS          VIA   -    MD0100PA00X+107200Y+040050X0200Y         S0      
317P52V_HS          VIA   -    MD0100PA00X+107200Y+039750X0200Y         S0      
317P52V_HS          VIA   -    MD0100PA00X+106900Y+038550X0200Y         S0      
317P52V_HS          VIA   -    MD0100PA00X+106900Y+038850X0200Y         S0      
317P52V_HS          VIA   -    MD0100PA00X+106000Y+038550X0200Y         S0      
317P52V_HS          VIA   -    MD0100PA00X+106300Y+038550X0200Y         S0      
317P52V_HS          VIA   -    MD0100PA00X+106600Y+038550X0200Y         S0      
317P52V_HS          VIA   -    MD0100PA00X+106000Y+038850X0200Y         S0      
317P52V_HS          VIA   -    MD0100PA00X+106300Y+038850X0200Y         S0      
317P52V_HS          VIA   -    MD0100PA00X+106600Y+038850X0200Y         S0      
317P52V_HS          VIA   -    MD0100PA00X+106600Y+039450X0200Y         S0      
317P52V_HS          VIA   -    MD0100PA00X+106300Y+039450X0200Y         S0      
317P52V_HS          VIA   -    MD0100PA00X+106000Y+039450X0200Y         S0      
317P52V_HS          VIA   -    MD0100PA00X+106600Y+039150X0200Y         S0      
317P52V_HS          VIA   -    MD0100PA00X+106300Y+039150X0200Y         S0      
317P52V_HS          VIA   -    MD0100PA00X+106000Y+039150X0200Y         S0      
317P52V_HS          VIA   -    MD0100PA00X+106900Y+040050X0200Y         S0      
317P52V_HS          VIA   -    MD0100PA00X+106000Y+040050X0200Y         S0      
317P52V_HS          VIA   -    MD0100PA00X+106300Y+040050X0200Y         S0      
317P52V_HS          VIA   -    MD0100PA00X+106600Y+040050X0200Y         S0      
317P52V_HS          VIA   -    MD0100PA00X+106900Y+039750X0200Y         S0      
317P52V_HS          VIA   -    MD0100PA00X+106000Y+039750X0200Y         S0      
317P52V_HS          VIA   -    MD0100PA00X+106300Y+039750X0200Y         S0      
317P52V_HS          VIA   -    MD0100PA00X+106600Y+039750X0200Y         S0      
317P52V_HS          VIA   -    MD0100PA00X+107200Y+034100X0200Y         S0      
317P52V_HS          VIA   -    MD0100PA00X+107200Y+035000X0200Y         S0      
317P52V_HS          VIA   -    MD0100PA00X+107200Y+035300X0200Y         S0      
317P52V_HS          VIA   -    MD0100PA00X+106900Y+034100X0200Y         S0      
317P52V_HS          VIA   -    MD0100PA00X+106900Y+035000X0200Y         S0      
317P52V_HS          VIA   -    MD0100PA00X+106900Y+035300X0200Y         S0      
317P52V_HS          VIA   -    MD0100PA00X+106000Y+035000X0200Y         S0      
317P52V_HS          VIA   -    MD0100PA00X+106300Y+035000X0200Y         S0      
317P52V_HS          VIA   -    MD0100PA00X+106600Y+035000X0200Y         S0      
317P52V_HS          VIA   -    MD0100PA00X+106000Y+035300X0200Y         S0      
317P52V_HS          VIA   -    MD0100PA00X+106300Y+035300X0200Y         S0      
317P52V_HS          VIA   -    MD0100PA00X+106600Y+035300X0200Y         S0      
317P52V_HS          VIA   -    MD0100PA00X+106000Y+034100X0200Y         S0      
317P52V_HS          VIA   -    MD0100PA00X+106300Y+034100X0200Y         S0      
317P52V_HS          VIA   -    MD0100PA00X+106600Y+034100X0200Y         S0      
317P52V_HS          VIA   -    MD0100PA00X+106600Y+034700X0200Y         S0      
317P52V_HS          VIA   -    MD0100PA00X+106300Y+034700X0200Y         S0      
317P52V_HS          VIA   -    MD0100PA00X+106000Y+034700X0200Y         S0      
317P52V_HS          VIA   -    MD0100PA00X+106600Y+034400X0200Y         S0      
317P52V_HS          VIA   -    MD0100PA00X+106300Y+034400X0200Y         S0      
317P52V_HS          VIA   -    MD0100PA00X+106000Y+034400X0200Y         S0      
317P52V_HS          VIA   -    MD0100PA00X+107200Y+033800X0200Y         S0      
317P52V_HS          VIA   -    MD0100PA00X+106900Y+033800X0200Y         S0      
317P52V_HS          VIA   -    MD0100PA00X+106000Y+033800X0200Y         S0      
317P52V_HS          VIA   -    MD0100PA00X+106300Y+033800X0200Y         S0      
317P52V_HS          VIA   -    MD0100PA00X+106600Y+033800X0200Y         S0      
317P52V_HS          VIA   -    MD0100PA00X+107200Y+029050X0200Y         S0      
317P52V_HS          VIA   -    MD0100PA00X+107200Y+030250X0200Y         S0      
317P52V_HS          VIA   -    MD0100PA00X+107200Y+030550X0200Y         S0      
317P52V_HS          VIA   -    MD0100PA00X+107200Y+029350X0200Y         S0      
317P52V_HS          VIA   -    MD0100PA00X+106900Y+029050X0200Y         S0      
317P52V_HS          VIA   -    MD0100PA00X+106000Y+029050X0200Y         S0      
317P52V_HS          VIA   -    MD0100PA00X+106300Y+029050X0200Y         S0      
317P52V_HS          VIA   -    MD0100PA00X+106600Y+029050X0200Y         S0      
317P52V_HS          VIA   -    MD0100PA00X+106900Y+030250X0200Y         S0      
317P52V_HS          VIA   -    MD0100PA00X+106900Y+030550X0200Y         S0      
317P52V_HS          VIA   -    MD0100PA00X+106000Y+030250X0200Y         S0      
317P52V_HS          VIA   -    MD0100PA00X+106300Y+030250X0200Y         S0      
317P52V_HS          VIA   -    MD0100PA00X+106600Y+030250X0200Y         S0      
317P52V_HS          VIA   -    MD0100PA00X+106000Y+030550X0200Y         S0      
317P52V_HS          VIA   -    MD0100PA00X+106300Y+030550X0200Y         S0      
317P52V_HS          VIA   -    MD0100PA00X+106600Y+030550X0200Y         S0      
317P52V_HS          VIA   -    MD0100PA00X+106600Y+029950X0200Y         S0      
317P52V_HS          VIA   -    MD0100PA00X+106300Y+029950X0200Y         S0      
317P52V_HS          VIA   -    MD0100PA00X+106000Y+029950X0200Y         S0      
317P52V_HS          VIA   -    MD0100PA00X+106900Y+029350X0200Y         S0      
317P52V_HS          VIA   -    MD0100PA00X+106000Y+029350X0200Y         S0      
317P52V_HS          VIA   -    MD0100PA00X+106300Y+029350X0200Y         S0      
317P52V_HS          VIA   -    MD0100PA00X+106600Y+029350X0200Y         S0      
317P52V_HS          VIA   -    MD0100PA00X+106600Y+029650X0200Y         S0      
317P52V_HS          VIA   -    MD0100PA00X+106300Y+029650X0200Y         S0      
317P52V_HS          VIA   -    MD0100PA00X+106000Y+029650X0200Y         S0      
317P52V_HS          VIA   -    MD0100PA00X+107200Y+024300X0200Y         S0      
317P52V_HS          VIA   -    MD0100PA00X+107200Y+024600X0200Y         S0      
317P52V_HS          VIA   -    MD0100PA00X+107200Y+025500X0200Y         S0      
317P52V_HS          VIA   -    MD0100PA00X+107200Y+025800X0200Y         S0      
317P52V_HS          VIA   -    MD0100PA00X+106900Y+024300X0200Y         S0      
317P52V_HS          VIA   -    MD0100PA00X+106900Y+024600X0200Y         S0      
317P52V_HS          VIA   -    MD0100PA00X+106900Y+025500X0200Y         S0      
317P52V_HS          VIA   -    MD0100PA00X+106900Y+025800X0200Y         S0      
317P52V_HS          VIA   -    MD0100PA00X+106000Y+025500X0200Y         S0      
317P52V_HS          VIA   -    MD0100PA00X+106300Y+025500X0200Y         S0      
317P52V_HS          VIA   -    MD0100PA00X+106600Y+025500X0200Y         S0      
317P52V_HS          VIA   -    MD0100PA00X+106000Y+025800X0200Y         S0      
317P52V_HS          VIA   -    MD0100PA00X+106300Y+025800X0200Y         S0      
317P52V_HS          VIA   -    MD0100PA00X+106600Y+025800X0200Y         S0      
317P52V_HS          VIA   -    MD0100PA00X+106000Y+024300X0200Y         S0      
317P52V_HS          VIA   -    MD0100PA00X+106300Y+024300X0200Y         S0      
317P52V_HS          VIA   -    MD0100PA00X+106600Y+024300X0200Y         S0      
317P52V_HS          VIA   -    MD0100PA00X+106000Y+024600X0200Y         S0      
317P52V_HS          VIA   -    MD0100PA00X+106300Y+024600X0200Y         S0      
317P52V_HS          VIA   -    MD0100PA00X+106600Y+024600X0200Y         S0      
317P52V_HS          VIA   -    MD0100PA00X+106600Y+025200X0200Y         S0      
317P52V_HS          VIA   -    MD0100PA00X+106300Y+025200X0200Y         S0      
317P52V_HS          VIA   -    MD0100PA00X+106000Y+025200X0200Y         S0      
317P52V_HS          VIA   -    MD0100PA00X+106600Y+024900X0200Y         S0      
317P52V_HS          VIA   -    MD0100PA00X+106300Y+024900X0200Y         S0      
317P52V_HS          VIA   -    MD0100PA00X+106000Y+024900X0200Y         S0      
327m0124            R5892 -1          A01X+018142Y+021683X0198Y0197R180 S1      
317m0124            VIA   -    MD0100PA00X+067608Y+029960X0200Y         S0      
327m0124            R203  -2   M      A10X+036100Y+030042X0198Y0197R090 S2      
317m0124            VIA   -    MD0100PA00X+020358Y+029750X0200Y         S0      
317m0124            VIA   -    MD0100PA00X+086700Y+029126X0200Y         S0      
327m0124            U27   -G          A10X+089006Y+029126X0320Y0360R270 S2      
317m0124            PU4   -8    D0360PA00X+020020Y+026720X0520Y    R270 S3      
317m0124            PU3   -8    D0360PA00X+035768Y+026720X0520Y    R270 S3      
317m0124            PU6   -8    D0360PA00X+067264Y+026720X0520Y    R270 S3      
317m0124            VIA   -    MD0100PA00X+018390Y+021683X0200Y         S0      
327m0125            R169  -2   M      A10X+056950Y+045058X0198Y0197R270 S2      
327m0125            R167  -2          A10X+057542Y+045750X0198Y0197     S2      
327m0125            R398  -2   M      A10X+056300Y+045324X0440Y0540R090 S2      
327m0125            R399  -1   M      A10X+054950Y+045058X0198Y0197R090 S2      
327m0125            C51   -1   M      A10X+053878Y+045058X0198Y0197R090 S2      
327m0125            R160  -1          A10X+053878Y+045542X0198Y0197R270 S2      
327m0125            VIA   -    M      A10X+054450Y+045058X0260Y         S2      
327m0126            R165  -2          A10X+054008Y+030050X0198Y0197R180 S2      
317m0126            PU2   -11   D0360PA00X+053878Y+026720X0520Y    R270 S3      
327SMB_BRICK0_SCL   R166  -2          A10X+054908Y+030050X0198Y0197R180 S2      
317SMB_BRICK0_SCL   PU2   -12   D0360PA00X+054665Y+026720X0520Y    R270 S3      
327SMB_BRICK0_SDA   R164  -2          A10X+053108Y+030050X0198Y0197R180 S2      
317SMB_BRICK0_SDA   PU2   -10   D0360PA00X+053091Y+026720X0520Y    R270 S3      
327m0127            PR50  -1   M      A10X+056240Y+030042X0180Y0200R090 S2      
317m0127            PU2   -14   D0360PA00X+056240Y+026720X0520Y    R270 S3      
327m0127            PR324 -2          A10X+040900Y+030042X0198Y0197R090 S2      
327m0128            R34   -2          A10X+092000Y+036108X0198Y0197R270 S2      
327m0128            R35   -2   M      A10X+091550Y+036108X0198Y0197R270 S2      
317m0128            VIA   -    M      A01X+091099Y+036108X0200Y         S2      
017m0128            VIA   -    M      A10X+091099Y+036108X0260Y         S2      
017m0128                  -    MD0100PA00X+091099Y+036108                       
317m0128            VIA   -    MD0100PA00X+078150Y+036270X0200Y         S0      
317m0128            J7    -S15  D0340PA00X+004878Y+031972X0500Y    R270 S3      
317m0128            VIA   -    MD0100PA00X+006344Y+035396X0200Y         S0      
327m0128            R113  -1   M      A10X+077858Y+036950X0198Y0197     S2      
327m0129            R168  -2          A10X+057908Y+043350X0198Y0197R180 S2      
327m0129            R169  -1          A10X+056950Y+044742X0198Y0197R270 S2      
327m0129            U23   -D   M      A10X+057606Y+044800X0320Y0360R090 S2      
327m0129            VIA   -    M      A10X+057898Y+043800X0260Y         S2      
327P12V_BRICK       PC99  -1          A01X+064242Y+003700X0180Y0200R180 S1      
327P12V_BRICK       R82   -1          A01X+064242Y+003300X0180Y0200R180 S1      
327P12V_BRICK       PR78  -2          A10X+024744Y+030358X0180Y0200R090 S2      
327P12V_BRICK       PC84  -1          A01X+023642Y+024750X0180Y0200R180 S1      
327P12V_BRICK       PC85  -1          A01X+023642Y+024300X0180Y0200R180 S1      
327P12V_BRICK       PR65  -2          A10X+040482Y+030358X0180Y0200R090 S2      
327P12V_BRICK       PC56  -1          A01X+039242Y+024700X0180Y0200R180 S1      
327P12V_BRICK       PC57  -1          A01X+039242Y+024250X0180Y0200R180 S1      
327P12V_BRICK       PR50  -2          A10X+056240Y+030358X0180Y0200R090 S2      
327P12V_BRICK       PC28  -1          A01X+054592Y+024800X0180Y0200R180 S1      
327P12V_BRICK       PC29  -1          A01X+054592Y+024350X0180Y0200R180 S1      
327P12V_BRICK       PR318 -2          A10X+071988Y+030358X0180Y0200R090 S2      
327P12V_BRICK       PC122 -1          A01X+070341Y+024800X0180Y0200R180 S1      
327P12V_BRICK       PC123 -1          A01X+070341Y+024350X0180Y0200R180 S1      
327P12V_BRICK       C91   -1          A01X+018127Y+020950X0180Y0200R270 S1      
327P12V_BRICK       R5894 -1          A01X+015898Y+024516X0180Y0200R180 S1      
317P12V_BRICK       VIA   -    M      A01X+015484Y+024473X0200Y         S2      
017P12V_BRICK       VIA   -    M      A10X+015484Y+024473X0260Y         S2      
017P12V_BRICK             -    MD0100PA00X+015484Y+024473                       
327P12V_BRICK       R5895 -1          A01X+014700Y+024120X0280Y0320R180 S1      
327P12V_BRICK       D4    -C          A01X+019740Y+021405X0850Y0890R270 S1      
327P12V_BRICK       U32   -26         A01X+016410Y+023250X0100Y0500R090 S1      
327P12V_BRICK       U32   -25         A01X+016410Y+022896X0100Y0500R090 S1      
327P12V_BRICK       U32   -24         A01X+016410Y+022541X0100Y0500R090 S1      
327P12V_BRICK       U32   -23         A01X+016410Y+022187X0100Y0500R090 S1      
327P12V_BRICK       U32   -21_2       A01X+016213Y+021700X0364Y0492R090 S1      
317P12V_BRICK       VIA   -    MD0100PA00X+016476Y+020985X0200Y    R090 S0      
317P12V_BRICK       VIA   -    MD0100PA00X+016766Y+020985X0200Y    R090 S0      
317P12V_BRICK       VIA   -    MD0100PA00X+016476Y+021305X0200Y    R090 S0      
317P12V_BRICK       VIA   -    MD0100PA00X+016766Y+021305X0200Y    R090 S0      
317P12V_BRICK       VIA   -    MD0100PA00X+017466Y+020265X0200Y    R090 S0      
317P12V_BRICK       VIA   -    MD0100PA00X+017466Y+020585X0200Y    R090 S0      
317P12V_BRICK       VIA   -    MD0100PA00X+017656Y+019705X0200Y    R090 S0      
317P12V_BRICK       VIA   -    MD0100PA00X+017946Y+019705X0200Y    R090 S0      
317P12V_BRICK       VIA   -    MD0100PA00X+018226Y+019705X0200Y    R090 S0      
317P12V_BRICK       VIA   -    MD0100PA00X+018526Y+020835X0200Y    R270 S0      
317P12V_BRICK       VIA   -    MD0100PA00X+018526Y+020535X0200Y    R270 S0      
317P12V_BRICK       VIA   -    MD0100PA00X+016285Y+022364X0180Y         S0      
317P12V_BRICK       VIA   -    MD0100PA00X+016285Y+022010X0180Y         S0      
317P12V_BRICK       VIA   -    MD0100PA00X+016535Y+023073X0180Y         S0      
317P12V_BRICK       VIA   -    MD0100PA00X+016535Y+022718X0180Y         S0      
317P12V_BRICK       VIA   -    MD0100PA00X+016535Y+022010X0180Y         S0      
317P12V_BRICK       VIA   -    MD0100PA00X+016535Y+022364X0180Y         S0      
317P12V_BRICK       VIA   -    MD0100PA00X+016285Y+023073X0180Y         S0      
317P12V_BRICK       VIA   -    MD0100PA00X+016285Y+022718X0180Y         S0      
317P12V_BRICK       PU6   -7   MD0830PA00X+074126Y+027720X1230Y    R270 S3      
317P12V_BRICK       PU6   -6   MD0830PA00X+072626Y+027720X1230Y    R270 S3      
317P12V_BRICK       VIA   -    MD0100PA00X+071988Y+030598X0200Y         S0      
317P12V_BRICK       VIA   -    MD0100PA00X+056240Y+030598X0200Y         S0      
317P12V_BRICK       VIA   -    MD0100PA00X+040492Y+030598X0200Y         S0      
317P12V_BRICK       VIA   -    MD0100PA00X+024744Y+030598X0200Y         S0      
327P12V_BRICK       R56   -1          A01X+078235Y+026203X0198Y0197R090 S1      
327P12V_BRICK       PR321 -1          A01X+070124Y+023750X0440Y0540R180 S1      
327P12V_BRICK       PR59  -1          A01X+054376Y+023750X0440Y0540R180 S1      
327P12V_BRICK       PR74  -1          A01X+039026Y+023650X0440Y0540R180 S1      
327P12V_BRICK       PR86  -1          A01X+023426Y+023700X0440Y0540R180 S1      
327P12V_BRICK       PC128 -1          A01X+072299Y+020400X0400Y0500R180 S1      
327P12V_BRICK       PC133 -1          A01X+072299Y+019650X0400Y0500R180 S1      
327P12V_BRICK       PC132 -1          A01X+070149Y+019650X0400Y0500R180 S1      
327P12V_BRICK       PC127 -1          A01X+070149Y+020400X0400Y0500R180 S1      
327P12V_BRICK       PC32  -1          A01X+065850Y+020400X0400Y0500R180 S1      
327P12V_BRICK       PC31  -1          A01X+068000Y+019650X0400Y0500R180 S1      
327P12V_BRICK       PC30  -1          A01X+068000Y+020400X0400Y0500R180 S1      
327P12V_BRICK       PC33  -1          A01X+065850Y+019650X0400Y0500R180 S1      
327P12V_BRICK       PC35  -1          A01X+063700Y+019650X0400Y0500R180 S1      
327P12V_BRICK       PC34  -1          A01X+063700Y+020400X0400Y0500R180 S1      
327P12V_BRICK       PC37  -1          A01X+061550Y+020400X0400Y0500R180 S1      
327P12V_BRICK       PC36  -1          A01X+061550Y+019650X0400Y0500R180 S1      
327P12V_BRICK       PC38  -1          A01X+059400Y+020400X0400Y0500R180 S1      
327P12V_BRICK       PC39  -1          A01X+059400Y+019650X0400Y0500R180 S1      
327P12V_BRICK       PC64  -1          A01X+041550Y+020450X0400Y0500R180 S1      
327P12V_BRICK       PC65  -1          A01X+041550Y+019700X0400Y0500R180 S1      
327P12V_BRICK       PC66  -1          A01X+039400Y+020450X0400Y0500R180 S1      
327P12V_BRICK       PC67  -1          A01X+039400Y+019700X0400Y0500R180 S1      
327P12V_BRICK       PC89  -1          A01X+035100Y+019650X0400Y0500R180 S1      
327P12V_BRICK       PC88  -1          A01X+035100Y+020450X0400Y0500R180 S1      
327P12V_BRICK       PC87  -1          A01X+037250Y+019700X0400Y0500R180 S1      
327P12V_BRICK       PC86  -1          A01X+037250Y+020450X0400Y0500R180 S1      
327P12V_BRICK       PC91  -1          A01X+032950Y+019650X0400Y0500R180 S1      
327P12V_BRICK       PC90  -1          A01X+032950Y+020450X0400Y0500R180 S1      
327P12V_BRICK       PC92  -1          A01X+030800Y+020450X0400Y0500R180 S1      
327P12V_BRICK       PC93  -1          A01X+030800Y+019650X0400Y0500R180 S1      
327P12V_BRICK       PC95  -1          A01X+028650Y+019650X0400Y0500R180 S1      
327P12V_BRICK       PC94  -1          A01X+028650Y+020450X0400Y0500R180 S1      
327P12V_BRICK       PL1   -1          A01X+064130Y+004520X0280Y0320R270 S1      
317P12V_BRICK       VIA   -    MD0100PA00X+064110Y+004810X0200Y         S0      
317P12V_BRICK       VIA   -    MD0100PA00X+063820Y+004650X0200Y         S0      
317P12V_BRICK       VIA   -    MD0100PA00X+063820Y+004400X0200Y         S0      
317P12V_BRICK       VIA   -    MD0100PA00X+064090Y+004230X0200Y         S0      
317P12V_BRICK       VIA   -    MD0100PA00X+071949Y+020550X0200Y         S0      
317P12V_BRICK       VIA   -    MD0100PA00X+071949Y+020300X0200Y         S0      
317P12V_BRICK       VIA   -    MD0100PA00X+071949Y+019800X0200Y         S0      
317P12V_BRICK       VIA   -    MD0100PA00X+071949Y+019550X0200Y         S0      
317P12V_BRICK       VIA   -    MD0100PA00X+069799Y+020550X0200Y         S0      
317P12V_BRICK       VIA   -    MD0100PA00X+069799Y+020300X0200Y         S0      
317P12V_BRICK       VIA   -    MD0100PA00X+069799Y+019800X0200Y         S0      
317P12V_BRICK       VIA   -    MD0100PA00X+069799Y+019550X0200Y         S0      
317P12V_BRICK       PC134 -1   MD0400PA00X+082398Y+024000X0600Y0600R270 S3      
317P12V_BRICK       PC135 -1   MD0400PA00X+077998Y+024000X0600Y0600R270 S3      
317P12V_BRICK       PC136 -1   MD0400PA00X+073598Y+024000X0600Y0600R270 S3      
317P12V_BRICK       VIA   -    MD0100PA00X+019716Y+020820X0200Y         S0      
317P12V_BRICK       VIA   -    MD0100PA00X+019716Y+020520X0200Y         S0      
317P12V_BRICK       VIA   -    MD0100PA00X+020016Y+020820X0200Y         S0      
317P12V_BRICK       VIA   -    MD0100PA00X+020016Y+020520X0200Y         S0      
317P12V_BRICK       VIA   -    MD0100PA00X+019416Y+020820X0200Y         S0      
317P12V_BRICK       VIA   -    MD0100PA00X+019416Y+020520X0200Y         S0      
317P12V_BRICK       PC96  -1   MD0400PA00X+035700Y+024000X0600Y0600R270 S3      
317P12V_BRICK       PC97  -1   MD0400PA00X+031250Y+024000X0600Y0600R270 S3      
317P12V_BRICK       PC98  -1   MD0400PA00X+026800Y+024000X0600Y0600R270 S3      
317P12V_BRICK       PC68  -1   MD0400PA00X+042850Y+024000X0600Y0600R270 S3      
317P12V_BRICK       PC69  -1   MD0400PA00X+051650Y+024000X0600Y0600R270 S3      
317P12V_BRICK       PC70  -1   MD0400PA00X+047250Y+024000X0600Y0600R270 S3      
317P12V_BRICK       PC40  -1   MD0400PA00X+057850Y+024000X0600Y0600R270 S3      
317P12V_BRICK       PC41  -1   MD0400PA00X+066650Y+024000X0600Y0600R270 S3      
317P12V_BRICK       PC42  -1   MD0400PA00X+062250Y+024000X0600Y0600R270 S3      
317P12V_BRICK       VIA   -    MD0100PA00X+043450Y+027119X0200Y         S0      
317P12V_BRICK       VIA   -    MD0100PA00X+043850Y+027119X0200Y         S0      
317P12V_BRICK       VIA   -    MD0100PA00X+044250Y+027119X0200Y         S0      
317P12V_BRICK       VIA   -    MD0100PA00X+043450Y+027519X0200Y         S0      
317P12V_BRICK       VIA   -    MD0100PA00X+043850Y+027519X0200Y         S0      
317P12V_BRICK       VIA   -    MD0100PA00X+044250Y+027519X0200Y         S0      
317P12V_BRICK       VIA   -    MD0100PA00X+043450Y+027919X0200Y         S0      
317P12V_BRICK       VIA   -    MD0100PA00X+043850Y+027919X0200Y         S0      
317P12V_BRICK       VIA   -    MD0100PA00X+044250Y+027919X0200Y         S0      
317P12V_BRICK       VIA   -    MD0100PA00X+044250Y+028319X0200Y         S0      
317P12V_BRICK       VIA   -    MD0100PA00X+043850Y+028319X0200Y         S0      
317P12V_BRICK       VIA   -    MD0100PA00X+043450Y+028319X0200Y         S0      
317P12V_BRICK       VIA   -    MD0100PA00X+028300Y+020600X0200Y         S0      
317P12V_BRICK       VIA   -    MD0100PA00X+028300Y+019600X0200Y         S0      
317P12V_BRICK       VIA   -    MD0100PA00X+028300Y+019850X0200Y         S0      
317P12V_BRICK       VIA   -    MD0100PA00X+028300Y+020350X0200Y         S0      
317P12V_BRICK       VIA   -    MD0100PA00X+030450Y+020600X0200Y         S0      
317P12V_BRICK       VIA   -    MD0100PA00X+030450Y+019600X0200Y         S0      
317P12V_BRICK       VIA   -    MD0100PA00X+030450Y+019850X0200Y         S0      
317P12V_BRICK       VIA   -    MD0100PA00X+030450Y+020350X0200Y         S0      
317P12V_BRICK       VIA   -    MD0100PA00X+032600Y+020600X0200Y         S0      
317P12V_BRICK       VIA   -    MD0100PA00X+032600Y+019600X0200Y         S0      
317P12V_BRICK       VIA   -    MD0100PA00X+032600Y+019850X0200Y         S0      
317P12V_BRICK       VIA   -    MD0100PA00X+032600Y+020350X0200Y         S0      
317P12V_BRICK       VIA   -    MD0100PA00X+034750Y+020600X0200Y         S0      
317P12V_BRICK       VIA   -    MD0100PA00X+034750Y+019600X0200Y         S0      
317P12V_BRICK       VIA   -    MD0100PA00X+034750Y+019850X0200Y         S0      
317P12V_BRICK       VIA   -    MD0100PA00X+034750Y+020350X0200Y         S0      
317P12V_BRICK       VIA   -    MD0100PA00X+036900Y+020600X0200Y         S0      
317P12V_BRICK       VIA   -    MD0100PA00X+036900Y+019600X0200Y         S0      
317P12V_BRICK       VIA   -    MD0100PA00X+036900Y+019850X0200Y         S0      
317P12V_BRICK       VIA   -    MD0100PA00X+036900Y+020350X0200Y         S0      
317P12V_BRICK       VIA   -    MD0100PA00X+039050Y+020600X0200Y         S0      
317P12V_BRICK       VIA   -    MD0100PA00X+039050Y+019600X0200Y         S0      
317P12V_BRICK       VIA   -    MD0100PA00X+039050Y+019850X0200Y         S0      
317P12V_BRICK       VIA   -    MD0100PA00X+039050Y+020350X0200Y         S0      
317P12V_BRICK       VIA   -    MD0100PA00X+041200Y+020600X0200Y         S0      
317P12V_BRICK       VIA   -    MD0100PA00X+041200Y+019600X0200Y         S0      
317P12V_BRICK       VIA   -    MD0100PA00X+041200Y+019850X0200Y         S0      
317P12V_BRICK       VIA   -    MD0100PA00X+041200Y+020350X0200Y         S0      
317P12V_BRICK       VIA   -    MD0100PA00X+059050Y+020550X0200Y         S0      
317P12V_BRICK       VIA   -    MD0100PA00X+059050Y+019550X0200Y         S0      
317P12V_BRICK       VIA   -    MD0100PA00X+059050Y+019800X0200Y         S0      
317P12V_BRICK       VIA   -    MD0100PA00X+059050Y+020300X0200Y         S0      
317P12V_BRICK       VIA   -    MD0100PA00X+061200Y+020550X0200Y         S0      
317P12V_BRICK       VIA   -    MD0100PA00X+061200Y+019550X0200Y         S0      
317P12V_BRICK       VIA   -    MD0100PA00X+061200Y+019800X0200Y         S0      
317P12V_BRICK       VIA   -    MD0100PA00X+061200Y+020300X0200Y         S0      
317P12V_BRICK       VIA   -    MD0100PA00X+063350Y+020550X0200Y         S0      
317P12V_BRICK       VIA   -    MD0100PA00X+063350Y+019550X0200Y         S0      
317P12V_BRICK       VIA   -    MD0100PA00X+063350Y+019800X0200Y         S0      
317P12V_BRICK       VIA   -    MD0100PA00X+063350Y+020300X0200Y         S0      
317P12V_BRICK       VIA   -    MD0100PA00X+065500Y+020550X0200Y         S0      
317P12V_BRICK       VIA   -    MD0100PA00X+065500Y+019550X0200Y         S0      
317P12V_BRICK       VIA   -    MD0100PA00X+065500Y+019800X0200Y         S0      
317P12V_BRICK       VIA   -    MD0100PA00X+065500Y+020300X0200Y         S0      
317P12V_BRICK       VIA   -    MD0100PA00X+067650Y+020550X0200Y         S0      
317P12V_BRICK       VIA   -    MD0100PA00X+067650Y+020300X0200Y         S0      
317P12V_BRICK       VIA   -    MD0100PA00X+067650Y+019800X0200Y         S0      
317P12V_BRICK       VIA   -    MD0100PA00X+067650Y+019550X0200Y         S0      
317P12V_BRICK       VIA   -    MD0100PA00X+027722Y+027108X0200Y         S0      
317P12V_BRICK       VIA   -    MD0100PA00X+028122Y+027108X0200Y         S0      
317P12V_BRICK       VIA   -    MD0100PA00X+028522Y+027108X0200Y         S0      
317P12V_BRICK       VIA   -    MD0100PA00X+027722Y+027508X0200Y         S0      
317P12V_BRICK       VIA   -    MD0100PA00X+028122Y+027508X0200Y         S0      
317P12V_BRICK       VIA   -    MD0100PA00X+028522Y+027508X0200Y         S0      
317P12V_BRICK       VIA   -    MD0100PA00X+027722Y+027908X0200Y         S0      
317P12V_BRICK       VIA   -    MD0100PA00X+028122Y+027908X0200Y         S0      
317P12V_BRICK       VIA   -    MD0100PA00X+028522Y+027908X0200Y         S0      
317P12V_BRICK       VIA   -    MD0100PA00X+028522Y+028308X0200Y         S0      
317P12V_BRICK       VIA   -    MD0100PA00X+028122Y+028308X0200Y         S0      
317P12V_BRICK       VIA   -    MD0100PA00X+027722Y+028308X0200Y         S0      
317P12V_BRICK       PU2   -7   MD0830PA00X+058378Y+027720X1230Y    R270 S3      
317P12V_BRICK       PU2   -6   MD0830PA00X+056878Y+027720X1230Y    R270 S3      
317P12V_BRICK       PU3   -7   MD0830PA00X+042630Y+027720X1230Y    R270 S3      
317P12V_BRICK       PU3   -6   MD0830PA00X+041130Y+027720X1230Y    R270 S3      
317P12V_BRICK       PU4   -7   MD0830PA00X+026882Y+027720X1230Y    R270 S3      
317P12V_BRICK       PU4   -6   MD0830PA00X+025382Y+027720X1230Y    R270 S3      
317P12V_BRICK       J1    -P4_3MD0402PA00X+079256Y+013941X0602Y    R270 S3      
317P12V_BRICK       J1    -P4_4MD0402PA00X+079256Y+014941X0602Y    R270 S3      
317P12V_BRICK       J1    -P4_7MD0402PA00X+078256Y+013941X0602Y    R270 S3      
317P12V_BRICK       J1    -P4_8MD0402PA00X+078256Y+014941X0602Y    R270 S3      
317P12V_BRICK       J1    -P5_3MD0402PA00X+075756Y+013941X0602Y    R270 S3      
317P12V_BRICK       J1    -P5_4MD0402PA00X+075756Y+014941X0602Y    R270 S3      
317P12V_BRICK       J1    -P5_7MD0402PA00X+074756Y+013941X0602Y    R270 S3      
317P12V_BRICK       J1    -P5_8MD0402PA00X+074756Y+014941X0602Y    R270 S3      
317P12V_BRICK       J1    -P6_3MD0402PA00X+072256Y+013941X0602Y    R270 S3      
317P12V_BRICK       J1    -P6_4MD0402PA00X+072256Y+014941X0602Y    R270 S3      
317P12V_BRICK       J1    -P6_7MD0402PA00X+071256Y+013941X0602Y    R270 S3      
317P12V_BRICK       J1    -P6_8MD0402PA00X+071256Y+014941X0602Y    R270 S3      
317P12V_BRICK       J2    -P6_5MD0402PA00X+048175Y+015968X0602Y         S3      
317P12V_BRICK       J2    -P6_6MD0402PA00X+048175Y+014968X0602Y         S3      
317P12V_BRICK       J2    -P6_7MD0402PA00X+048175Y+013968X0602Y         S3      
317P12V_BRICK       J2    -P5_5MD0402PA00X+044675Y+015968X0602Y         S3      
317P12V_BRICK       J2    -P5_6MD0402PA00X+044675Y+014968X0602Y         S3      
317P12V_BRICK       J2    -P5_7MD0402PA00X+044675Y+013968X0602Y         S3      
317P12V_BRICK       J2    -P6_1MD0402PA00X+047175Y+015968X0602Y         S3      
317P12V_BRICK       J2    -P6_2MD0402PA00X+047175Y+014968X0602Y         S3      
317P12V_BRICK       J2    -P6_3MD0402PA00X+047175Y+013968X0602Y         S3      
317P12V_BRICK       J2    -P4_1MD0402PA00X+040175Y+015968X0602Y         S3      
317P12V_BRICK       J2    -P4_2MD0402PA00X+040175Y+014968X0602Y         S3      
317P12V_BRICK       J2    -P4_3MD0402PA00X+040175Y+013968X0602Y         S3      
317P12V_BRICK       J2    -P4_5MD0402PA00X+041175Y+015968X0602Y         S3      
317P12V_BRICK       J2    -P4_6MD0402PA00X+041175Y+014968X0602Y         S3      
317P12V_BRICK       J2    -P4_7MD0402PA00X+041175Y+013968X0602Y         S3      
317P12V_BRICK       J2    -P5_1MD0402PA00X+043675Y+015968X0602Y         S3      
317P12V_BRICK       J2    -P5_2MD0402PA00X+043675Y+014968X0602Y         S3      
317P12V_BRICK       J2    -P5_3MD0402PA00X+043675Y+013968X0602Y         S3      
317P12V_BRICK       J1    -P4_1MD0402PA00X+079256Y+011941X0602Y    R270 S3      
317P12V_BRICK       J1    -P4_2MD0402PA00X+079256Y+012941X0602Y    R270 S3      
317P12V_BRICK       J1    -P4_5MD0402PA00X+078256Y+011941X0602Y    R270 S3      
317P12V_BRICK       J1    -P4_6MD0402PA00X+078256Y+012941X0602Y    R270 S3      
317P12V_BRICK       J1    -P5_1MD0402PA00X+075756Y+011941X0602Y    R270 S3      
317P12V_BRICK       J1    -P5_2MD0402PA00X+075756Y+012941X0602Y    R270 S3      
317P12V_BRICK       J1    -P5_5MD0402PA00X+074756Y+011941X0602Y    R270 S3      
317P12V_BRICK       J1    -P5_6MD0402PA00X+074756Y+012941X0602Y    R270 S3      
317P12V_BRICK       J1    -P6_1MD0402PA00X+072256Y+011941X0602Y    R270 S3      
317P12V_BRICK       J1    -P6_2MD0402PA00X+072256Y+012941X0602Y    R270 S3      
317P12V_BRICK       J1    -P6_5MD0402PA00X+071256Y+011941X0602Y    R270 S3      
317P12V_BRICK       J1    -P6_6MD0402PA00X+071256Y+012941X0602Y    R270 S3      
317P12V_BRICK       J2    -P6_8MD0402PA00X+048175Y+012968X0602Y         S3      
317P12V_BRICK       J2    -P5_8MD0402PA00X+044675Y+012968X0602Y         S3      
317P12V_BRICK       J2    -P6_4MD0402PA00X+047175Y+012968X0602Y         S3      
317P12V_BRICK       J2    -P4_4MD0402PA00X+040175Y+012968X0602Y         S3      
317P12V_BRICK       J2    -P4_8MD0402PA00X+041175Y+012968X0602Y         S3      
317P12V_BRICK       J2    -P5_4MD0402PA00X+043675Y+012968X0602Y         S3      
317m0130            VIA   -    M      A01X+091626Y+035500X0300Y         S1      
017m0130            VIA   -    M      A10X+091626Y+035500X0200Y         S1      
017m0130                  -    MD0100PA00X+091626Y+035500                       
327m0130            U9    -4          A10X+091626Y+035082X0180Y0520     S2      
327m0130            R35   -1          A10X+091550Y+035792X0198Y0197R270 S2      
327m0131            R160  -2          A10X+053878Y+045858X0198Y0197R270 S2      
317m0131            PU2   -2    D0630PA00X+053878Y+047720X0930Y    R270 S3      
317GND_BUSBAR       J5    -B1   D0402PA00X+123602Y+028693X0602Y         S3      
327m0132            PR52  -1          A10X+052303Y+030042X0198Y0197R270 S2      
317m0132            PU2   -9    D0360PA00X+052303Y+026720X0520Y    R270 S3      
327BRICK0_PMBADD    PR58  -2          A10X+055453Y+030042X0198Y0197R090 S2      
317BRICK0_PMBADD    PU2   -13   D0360PA00X+055453Y+026720X0520Y    R270 S3      
317P52V_BUSBAR      VIA   -    M      A01X+109200Y+008250X0200Y         S2      
017P52V_BUSBAR      VIA   -    M      A10X+109200Y+008250X0260Y         S2      
017P52V_BUSBAR            -    MD0100PA00X+109200Y+008250                       
327P52V_BUSBAR      R5884 -1          A01X+109626Y+008250X0440Y0540R180 S1      
317P52V_BUSBAR      J5    -A1   D0402PA00X+122602Y+028693X0602Y0602     S3      
327GND              PC99  -2          A01X+064558Y+003700X0180Y0200R180 S1      
327GND              PC102 -2          A01X+069140Y+005088X0180Y0200R270 S1      
327GND              PC84  -2          A01X+023958Y+024750X0180Y0200R180 S1      
327GND              PC85  -2          A01X+023958Y+024300X0180Y0200R180 S1      
327GND              PC56  -2          A01X+039558Y+024700X0180Y0200R180 S1      
327GND              PC57  -2          A01X+039558Y+024250X0180Y0200R180 S1      
327GND              PC28  -2          A01X+054908Y+024800X0180Y0200R180 S1      
327GND              PC29  -2          A01X+054908Y+024350X0180Y0200R180 S1      
327GND              PC122 -2          A01X+070656Y+024800X0180Y0200R180 S1      
327GND              PC123 -2          A01X+070656Y+024350X0180Y0200R180 S1      
327GND              C91   -2          A01X+018127Y+021265X0180Y0200R270 S1      
327GND              C93   -2          A01X+015318Y+021578X0180Y0200R090 S1      
327GND              R5899 -1          A01X+015898Y+024114X0198Y0197     S1      
327GND              C95   -1          A01X+015220Y+024120X0280Y0320R180 S1      
327GND              D5    -A          A01X+013387Y+025850X0670Y0990R270 S1      
317GND              VIA   -    MD0100PA00X+109050Y+037650X0200Y         S0      
317GND              VIA   -    MD0100PA00X+073210Y+033240X0200Y         S0      
327GND              C98   -2   M      A10X+017830Y+022352X0198Y0197     S2      
317GND              VIA   -    MD0100PA00X+114150Y+012050X0200Y         S0      
327GND              R5916 -2          A10X+114150Y+011758X0198Y0197R270 S2      
317GND              VIA   -    MD0100PA00X+114150Y+013458X0200Y         S0      
317GND              VIA   -    MD0100PA00X+114150Y+012442X0200Y         S0      
317GND              VIA   -    MD0100PA00X+115400Y+015150X0200Y         S0      
327GND              C100  -2   M      A10X+115358Y+015400X0198Y0197R180 S2      
317GND              VIA   -    MD0100PA00X+115930Y+012970X0200Y         S0      
327GND              U36   -S          A10X+115244Y+013426X0320Y0360R090 S2      
317GND              VIA   -    MD0100PA00X+106890Y+011000X0200Y         S0      
327GND              C102  -2          A10X+107042Y+011400X0198Y0197     S2      
317GND              VIA   -    MD0100PA00X+108474Y+010800X0200Y         S0      
327GND              U37   -S          A10X+108124Y+010844X0320Y0360R180 S2      
327GND              C101  -2          A10X+106350Y+012450X0400Y0500R090 S2      
317GND              VIA   -    MD0100PA00X+108426Y+015260X0200Y         S0      
327GND              U40   -S          A10X+108426Y+014906X0320Y0360     S2      
317GND              VIA   -    MD0100PA00X+106500Y+015642X0200Y         S0      
327GND              R5933 -2          A10X+106750Y+015642X0198Y0197R090 S2      
317GND              VIA   -    MD0100PA00X+110008Y+013992X0200Y         S0      
327GND              R5931 -2          A10X+110450Y+013992X0198Y0197R090 S2      
317GND              VIA   -    MD0100PA00X+111350Y+014750X0200Y         S0      
327GND              U39   -S          A10X+111394Y+015076X0320Y0360R090 S2      
327GND              C94   -2          A01X+018142Y+022083X0198Y0197     S1      
327GND              R5901 -2          A01X+018148Y+022482X0198Y0197     S1      
327GND              C96   -2          A01X+018142Y+023133X0198Y0197     S1      
327GND              C97   -2          A01X+018142Y+023833X0198Y0197     S1      
327GND              R5900 -2          A01X+018142Y+024233X0198Y0197     S1      
317GND              VIA   -    MD0100PA00X+018435Y+021265X0200Y         S0      
327GND              U32   -2          A01X+016961Y+022029X0100Y0320R090 S1      
317GND              VIA   -    MD0100PA00X+017293Y+021911X0200Y    R270 S0      
317GND              VIA   -    MD0100PA00X+014340Y+025536X0200Y         S0      
317GND              VIA   -    MD0100PA00X+014040Y+025536X0200Y         S0      
317GND              VIA   -    MD0100PA00X+014340Y+026136X0200Y         S0      
317GND              VIA   -    MD0100PA00X+014040Y+026136X0200Y         S0      
317GND              VIA   -    MD0100PA00X+014340Y+025836X0200Y         S0      
317GND              VIA   -    MD0100PA00X+014040Y+025836X0200Y         S0      
317GND              J7    -P13 MD0410PA00X+004878Y+025929X0580Y    R270 S3      
317GND              J7    -P14 MD0410PA00X+004878Y+025260X0580Y    R270 S3      
317GND              J7    -P15 MD0410PA00X+004878Y+023929X0580Y    R270 S3      
317GND              J7    -P16 MD0410PA00X+004878Y+023260X0580Y    R270 S3      
327GND              U32   -3          A01X+016961Y+022226X0100Y0320R090 S1      
317GND              VIA   -    MD0100PA00X+018382Y+022090X0200Y    R270 S0      
317GND              VIA   -    MD0100PA00X+017271Y+022226X0200Y    R270 S0      
317GND              VIA   -    MD0100PA00X+015348Y+021335X0200Y    R090 S0      
317GND              VIA   -    MD0100PA00X+015514Y+024023X0200Y    R270 S0      
327GND              C92   -2          A10X+014723Y+023956X0400Y0500R090 S2      
317GND              VIA   -    MD0100PA00X+112067Y+054700X0200Y    R270 S0      
317GND              VIA   -    MD0100PA00X+112367Y+054700X0200Y    R270 S0      
317GND              VIA   -    MD0100PA00X+112067Y+055000X0200Y    R270 S0      
317GND              VIA   -    MD0100PA00X+112367Y+055000X0200Y    R270 S0      
317GND              VIA   -    MD0100PA00X+112067Y+055300X0200Y    R270 S0      
317GND              VIA   -    M      A01X+112367Y+055300X0200Y    R270 S2      
017GND              VIA   -    M      A10X+112367Y+055300X0260Y    R270 S2      
017GND                    -    MD0100PA00X+112367Y+055300                       
317GND              VIA   -    MD0100PA00X+112067Y+053800X0200Y    R270 S0      
317GND              VIA   -    M      A01X+112367Y+053800X0200Y    R270 S2      
017GND              VIA   -    M      A10X+112367Y+053800X0260Y    R270 S2      
017GND                    -    MD0100PA00X+112367Y+053800                       
317GND              VIA   -    MD0100PA00X+112367Y+054100X0200Y    R270 S0      
317GND              VIA   -    MD0100PA00X+112367Y+054400X0200Y    R270 S0      
317GND              VIA   -    MD0100PA00X+112067Y+054100X0200Y    R270 S0      
317GND              VIA   -    MD0100PA00X+112067Y+054400X0200Y    R270 S0      
317GND              VIA   -    MD0100PA00X+112503Y+001813X0200Y    R090 S0      
317GND              VIA   -    MD0100PA00X+112503Y+002113X0200Y    R090 S0      
317GND              VIA   -    MD0100PA00X+112753Y+002113X0200Y    R090 S0      
317GND              VIA   -    MD0100PA00X+112753Y+001813X0200Y    R090 S0      
317GND              VIA   -    MD0100PA00X+113003Y+001813X0200Y    R090 S0      
317GND              VIA   -    MD0100PA00X+113253Y+001813X0200Y    R090 S0      
317GND              VIA   -    MD0100PA00X+113253Y+002113X0200Y    R090 S0      
317GND              VIA   -    MD0100PA00X+113003Y+002113X0200Y    R090 S0      
317GND              VIA   -    MD0100PA00X+113503Y+001813X0200Y    R090 S0      
317GND              VIA   -    MD0100PA00X+113503Y+002113X0200Y    R090 S0      
317GND              VIA   -    MD0100PA00X+110696Y+002113X0200Y    R090 S0      
317GND              VIA   -    MD0100PA00X+110696Y+001813X0200Y    R090 S0      
317GND              VIA   -    MD0100PA00X+110196Y+002113X0200Y    R090 S0      
317GND              VIA   -    MD0100PA00X+110446Y+002113X0200Y    R090 S0      
317GND              VIA   -    MD0100PA00X+110446Y+001813X0200Y    R090 S0      
317GND              VIA   -    MD0100PA00X+110196Y+001813X0200Y    R090 S0      
317GND              VIA   -    MD0100PA00X+109946Y+001813X0200Y    R090 S0      
317GND              VIA   -    MD0100PA00X+109946Y+002113X0200Y    R090 S0      
317GND              VIA   -    MD0100PA00X+109696Y+002113X0200Y    R090 S0      
317GND              VIA   -    MD0100PA00X+109696Y+001813X0200Y    R090 S0      
317GND              VIA   -    MD0100PA00X+110710Y+005674X0200Y    R090 S0      
317GND              VIA   -    MD0100PA00X+110710Y+005374X0200Y    R090 S0      
317GND              VIA   -    MD0100PA00X+110210Y+005674X0200Y    R090 S0      
317GND              VIA   -    MD0100PA00X+110460Y+005674X0200Y    R090 S0      
317GND              VIA   -    MD0100PA00X+110460Y+005374X0200Y    R090 S0      
317GND              VIA   -    MD0100PA00X+110210Y+005374X0200Y    R090 S0      
317GND              VIA   -    MD0100PA00X+109960Y+005374X0200Y    R090 S0      
317GND              VIA   -    MD0100PA00X+109960Y+005674X0200Y    R090 S0      
317GND              VIA   -    MD0100PA00X+109710Y+005674X0200Y    R090 S0      
317GND              VIA   -    MD0100PA00X+109710Y+005374X0200Y    R090 S0      
317GND              VIA   -    MD0100PA00X+110710Y+003858X0200Y    R090 S0      
317GND              VIA   -    MD0100PA00X+110710Y+003558X0200Y    R090 S0      
317GND              VIA   -    MD0100PA00X+110210Y+003858X0200Y    R090 S0      
317GND              VIA   -    MD0100PA00X+110460Y+003858X0200Y    R090 S0      
317GND              VIA   -    MD0100PA00X+110460Y+003558X0200Y    R090 S0      
317GND              VIA   -    MD0100PA00X+110210Y+003558X0200Y    R090 S0      
317GND              VIA   -    MD0100PA00X+109960Y+003558X0200Y    R090 S0      
317GND              VIA   -    MD0100PA00X+109960Y+003858X0200Y    R090 S0      
317GND              VIA   -    MD0100PA00X+109710Y+003858X0200Y    R090 S0      
317GND              VIA   -    MD0100PA00X+109710Y+003558X0200Y    R090 S0      
317GND              VIA   -    MD0100PA00X+111950Y+008300X0200Y         S0      
327GND              C89   -2          A01X+111590Y+008300X0280Y0320R270 S1      
317GND              VIA   -    MD0100PA00X+111950Y+008600X0200Y         S0      
327GND              R5885 -2          A01X+111308Y+008800X0198Y0197     S1      
317GND              VIA   -    MD0100PA00X+111300Y+010124X0200Y         S0      
327GND              U19   -3          A01X+110972Y+010124X0220Y0320R090 S1      
317GND              VIA   -    MD0100PA00X+109510Y+009950X0200Y         S0      
327GND              C90   -2          A01X+109510Y+009708X0198Y0197R090 S1      
317GND              VIA   -    MD0100PA00X+109100Y+009950X0200Y         S0      
327GND              R5888 -2          A01X+109100Y+009708X0198Y0197R090 S1      
327GND              R5887 -2   M      A01X+117508Y+011150X0198Y0197     S1      
327GND              PD7   -A          A01X+118356Y+013047X0950Y1300R270 S1      
317GND              VIA   -    M      A01X+065230Y+005680X0200Y         S2      
017GND              VIA   -    M      A10X+065230Y+005680X0260Y         S2      
017GND                    -    MD0100PA00X+065230Y+005680                       
317GND              VIA   -    MD0100PA00X+065530Y+005680X0200Y         S0      
317GND              VIA   -    M      A01X+066020Y+005680X0200Y         S2      
017GND              VIA   -    M      A10X+066020Y+005680X0260Y         S2      
017GND                    -    MD0100PA00X+066020Y+005680                       
317GND              VIA   -    MD0100PA00X+066320Y+005680X0200Y         S0      
317GND              VIA   -    M      A01X+066810Y+005680X0200Y         S2      
017GND              VIA   -    M      A10X+066810Y+005680X0260Y         S2      
017GND                    -    MD0100PA00X+066810Y+005680                       
317GND              VIA   -    MD0100PA00X+067110Y+005680X0200Y         S0      
327GND              PC566 -2          A01X+066950Y+005270X0400Y0500R270 S1      
327GND              PC567 -2          A01X+066160Y+005270X0400Y0500R270 S1      
327GND              PC568 -2          A01X+065370Y+005270X0400Y0500R270 S1      
317GND              VIA   -    M      A01X+064798Y+003700X0200Y         S2      
017GND              VIA   -    M      A10X+064798Y+003700X0260Y         S2      
017GND                    -    MD0100PA00X+064798Y+003700                       
327GND              U25   -10         A10X+078272Y+033648X0160Y0440R090 S2      
327GND              PC8   -1          A10X+109334Y+041734X0280Y0320R180 S2      
317GND              VIA   -    MD0100PA00X+109044Y+041734X0200Y         S0      
317GND              VIA   -    MD0100PA00X+107072Y+017858X0200Y         S0      
327GND              U29   -4          A01X+107072Y+017478X0150Y0460R180 S1      
317GND              VIA   -    MD0100PA00X+115500Y+012491X0200Y         S0      
327GND              PJ1   -2          A01X+115154Y+012491X0280Y0320R270 S1      
317GND              VIA   -    MD0100PA00X+106760Y+012320X0200Y    R270 S0      
317GND              VIA   -    MD0100PA00X+107040Y+012320X0200Y    R270 S0      
317GND              VIA   -    MD0100PA00X+107320Y+012320X0200Y         S0      
317GND              VIA   -    MD0100PA00X+107320Y+012880X0200Y         S0      
317GND              VIA   -    MD0100PA00X+107320Y+012600X0200Y         S0      
327GND              PC487 -2          A01X+106855Y+012747X0460Y0620R090 S1      
317GND              VIA   -    MD0100PA00X+103450Y+014200X0200Y         S0      
327GND              PC4   -2          A10X+103442Y+013950X0198Y0197     S2      
317GND              PC113 -2   MD0420PA00X+075367Y+053900X0620Y         S3      
317GND              PC115 -2   MD0420PA00X+065767Y+053900X0620Y         S3      
317GND              VIA   -    MD0100PA00X+088300Y+035850X0200Y    R270 S0      
327GND              C10   -1          A10X+088300Y+035608X0198Y0197R090 S2      
317GND              VIA   -    MD0100PA00X+087800Y+035848X0200Y    R270 S0      
327GND              R37   -2          A10X+087800Y+035608X0198Y0197R270 S2      
317GND              VIA   -    MD0100PA00X+084476Y+033608X0200Y         S0      
327GND              U8    -3          A10X+084476Y+034018X0180Y0520     S2      
317GND              VIA   -    MD0100PA00X+083561Y+035559X0200Y    R270 S0      
327GND              C7    -1          A10X+083250Y+035808X0198Y0197R090 S2      
317GND              VIA   -    MD0100PA00X+081398Y+035700X0200Y         S0      
327GND              R103  -2          A10X+081158Y+035700X0198Y0197R180 S2      
317GND              VIA   -    MD0100PA00X+081398Y+036200X0200Y         S0      
327GND              R97   -2          A10X+081158Y+036200X0198Y0197R180 S2      
317GND              VIA   -    MD0100PA00X+082594Y+033956X0200Y    R270 S0      
327GND              U6    -3          A10X+082594Y+034226X0170Y0240     S2      
317GND              VIA   -    MD0100PA00X+074250Y+036150X0200Y         S0      
327GND              C48   -2          A10X+074492Y+036150X0198Y0197     S2      
317GND              VIA   -    MD0100PA00X+078650Y+033648X0200Y         S0      
317GND              VIA   -    MD0100PA00X+082750Y+032900X0200Y         S0      
327GND              R23   -2          A10X+082750Y+032658X0198Y0197R270 S2      
317GND              VIA   -    MD0100PA00X+081950Y+032900X0200Y         S0      
327GND              R22   -2          A10X+081950Y+032658X0198Y0197R270 S2      
317GND              VIA   -    MD0100PA00X+088300Y+029392X0200Y         S0      
327GND              R43   -1          A10X+087000Y+029392X0198Y0197R270 S2      
327GND              R44   -1   M      A10X+087500Y+029392X0198Y0197R270 S2      
327GND              R45   -1   M      A10X+088000Y+029392X0198Y0197R270 S2      
317GND              VIA   -    MD0100PA00X+089336Y+029874X0200Y         S0      
327GND              U27   -S          A10X+089006Y+029874X0320Y0360R270 S2      
317GND              VIA   -    MD0100PA00X+086500Y+031320X0200Y    R270 S0      
327GND              U10   -4          A10X+086500Y+031810X0220Y0680     S2      
317GND              VIA   -    MD0100PA00X+083758Y+032100X0200Y         S0      
327GND              R188  -1          A10X+083758Y+032350X0198Y0197     S2      
317GND              VIA   -    MD0100PA00X+085600Y+026052X0200Y         S0      
327GND              R138  -2          A10X+085600Y+026292X0198Y0197R090 S2      
317GND              VIA   -    MD0100PA00X+085100Y+026052X0200Y         S0      
327GND              R137  -2          A10X+085100Y+026292X0198Y0197R090 S2      
317GND              VIA   -    MD0100PA00X+084600Y+026052X0200Y         S0      
327GND              R136  -2          A10X+084600Y+026292X0198Y0197R090 S2      
317GND              VIA   -    MD0100PA00X+084100Y+026052X0200Y    R270 S0      
327GND              R95   -2          A10X+084100Y+026292X0198Y0197R090 S2      
317GND              VIA   -    MD0100PA00X+082600Y+026052X0200Y    R180 S0      
327GND              R21   -2          A10X+082600Y+026292X0198Y0197R090 S2      
317GND              VIA   -    MD0100PA00X+083600Y+026050X0200Y    R270 S0      
327GND              R94   -2          A10X+083600Y+026292X0198Y0197R090 S2      
317GND              VIA   -    MD0100PA00X+083100Y+026050X0200Y    R270 S0      
327GND              R93   -2          A10X+083100Y+026292X0198Y0197R090 S2      
327GND              C4    -2          A10X+081100Y+027292X0198Y0197R090 S2      
317GND              VIA   -    MD0100PA00X+080850Y+027292X0200Y    R270 S0      
317GND              VIA   -    MD0100PA00X+084808Y+030650X0200Y    R180 S0      
327GND              U4    -12         A10X+084808Y+031100X0140Y0590R180 S2      
317GND              VIA   -    MD0100PA00X+087750Y+028348X0200Y         S0      
327GND              C16   -2          A10X+087750Y+028108X0198Y0197R270 S2      
317GND              VIA   -    MD0100PA00X+088400Y+028348X0200Y         S0      
327GND              C18   -2          A10X+088400Y+028108X0198Y0197R270 S2      
317GND              VIA   -    MD0100PA00X+089450Y+028348X0200Y         S0      
327GND              C47   -2          A10X+089450Y+028108X0198Y0197R270 S2      
317GND              VIA   -    MD0100PA00X+090594Y+030650X0200Y         S0      
327GND              U5    -3          A10X+090594Y+030926X0170Y0240     S2      
317GND              VIA   -    MD0100PA00X+090500Y+028348X0200Y         S0      
327GND              C17   -2          A10X+090500Y+028108X0198Y0197R270 S2      
317GND              VIA   -    MD0100PA00X+094700Y+029348X0200Y         S0      
327GND              C66   -2          A10X+094700Y+029108X0198Y0197R270 S2      
317GND              VIA   -    MD0100PA00X+094000Y+029348X0200Y         S0      
327GND              C67   -2          A10X+094000Y+029108X0198Y0197R270 S2      
327GND              C1    -2          A10X+093320Y+031231X0198Y0197R090 S2      
317GND              VIA   -    MD0100PA00X+093320Y+030991X0200Y         S0      
317GND              VIA   -    MD0100PA00X+091450Y+029200X0200Y         S0      
327GND              R187  -1          A10X+091450Y+029442X0198Y0197R270 S2      
317GND              VIA   -    MD0100PA00X+093300Y+029348X0200Y         S0      
327GND              C14   -2          A10X+093300Y+029108X0198Y0197R270 S2      
317GND              VIA   -    MD0100PA00X+091550Y+028348X0200Y         S0      
327GND              C15   -2          A10X+091550Y+028108X0198Y0197R270 S2      
317GND              VIA   -    MD0100PA00X+094104Y+034447X0200Y    R090 S0      
327GND              U1    -4          A10X+094104Y+034017X0140Y0560R180 S2      
317GND              VIA   -    MD0100PA00X+092700Y+036108X0200Y         S0      
327GND              C9    -1          A10X+092450Y+036108X0198Y0197R090 S2      
317GND              VIA   -    MD0100PA00X+090800Y+032798X0200Y         S0      
327GND              R140  -1          A10X+090800Y+032558X0198Y0197R090 S2      
317GND              VIA   -    MD0100PA00X+091626Y+033708X0200Y         S0      
327GND              U9    -3          A10X+091626Y+034118X0180Y0520     S2      
317GND              VIA   -    MD0100PA00X+091250Y+032798X0200Y    R180 S0      
327GND              C5    -2          A10X+091250Y+032558X0198Y0197R270 S2      
317GND              VIA   -    MD0100PA00X+090106Y+035234X0200Y         S0      
327GND              U20   -S          A10X+090106Y+034924X0320Y0360R270 S2      
317GND              VIA   -    MD0100PA00X+054950Y+044502X0200Y         S0      
327GND              R399  -2          A10X+054950Y+044742X0198Y0197R090 S2      
317GND              VIA   -    MD0100PA00X+058950Y+044650X0200Y         S0      
327GND              C55   -1          A10X+058950Y+044892X0198Y0197R270 S2      
317GND              JP2   -2   MD0460PA00X+101100Y+010800X0660Y    R090 S3      
327GND              PD8   -A          A01X+110439Y+054550X0990Y1300     S1      
317GND              VIA   -    MD0100PA00X+084949Y+020600X0200Y         S0      
317GND              VIA   -    MD0100PA00X+084949Y+020350X0200Y         S0      
317GND              VIA   -    MD0100PA00X+084949Y+019850X0200Y         S0      
317GND              VIA   -    MD0100PA00X+084949Y+019600X0200Y         S0      
317GND              VIA   -    MD0100PA00X+073349Y+020550X0200Y         S0      
317GND              VIA   -    MD0100PA00X+073349Y+020300X0200Y         S0      
317GND              VIA   -    MD0100PA00X+073349Y+019800X0200Y         S0      
317GND              VIA   -    MD0100PA00X+073349Y+019550X0200Y         S0      
327GND              PC128 -2          A01X+072999Y+020400X0400Y0500R180 S1      
327GND              PC133 -2          A01X+072999Y+019650X0400Y0500R180 S1      
317GND              VIA   -    MD0100PA00X+071199Y+020550X0200Y         S0      
317GND              VIA   -    MD0100PA00X+071199Y+020300X0200Y         S0      
317GND              VIA   -    MD0100PA00X+071199Y+019800X0200Y         S0      
317GND              VIA   -    MD0100PA00X+071199Y+019550X0200Y         S0      
327GND              PC132 -2          A01X+070849Y+019650X0400Y0500R180 S1      
327GND              PC127 -2          A01X+070849Y+020400X0400Y0500R180 S1      
327GND              C36   -2          A10X+095200Y+037020X0460Y0620R270 S2      
327GND              C34   -2          A10X+094250Y+037020X0460Y0620R270 S2      
327GND              C28   -2          A10X+091350Y+037020X0460Y0620R270 S2      
327GND              C30   -2          A10X+092350Y+037020X0460Y0620R270 S2      
327GND              C32   -2          A10X+093300Y+037020X0460Y0620R270 S2      
327GND              C38   -2          A10X+087550Y+037020X0460Y0620R270 S2      
327GND              C24   -2          A10X+089450Y+037020X0460Y0620R270 S2      
327GND              C22   -2          A10X+088500Y+037020X0460Y0620R270 S2      
327GND              C26   -2          A10X+090400Y+037020X0460Y0620R270 S2      
327GND              C42   -2          A10X+085650Y+037020X0460Y0620R270 S2      
327GND              C44   -2          A10X+084700Y+037020X0460Y0620R270 S2      
327GND              C40   -2          A10X+086600Y+037020X0460Y0620R270 S2      
327GND              PR86  -2          A01X+024174Y+023700X0440Y0540R180 S1      
327GND              PR74  -2          A01X+039774Y+023650X0440Y0540R180 S1      
327GND              PR59  -2          A01X+055124Y+023750X0440Y0540R180 S1      
327GND              PR321 -2          A01X+070872Y+023750X0440Y0540R180 S1      
327GND              PC31  -2          A01X+068700Y+019650X0400Y0500R180 S1      
327GND              PC30  -2          A01X+068700Y+020400X0400Y0500R180 S1      
327GND              PC33  -2          A01X+066550Y+019650X0400Y0500R180 S1      
327GND              PC32  -2          A01X+066550Y+020400X0400Y0500R180 S1      
327GND              PC35  -2          A01X+064400Y+019650X0400Y0500R180 S1      
327GND              PC34  -2          A01X+064400Y+020400X0400Y0500R180 S1      
327GND              PC37  -2          A01X+062250Y+020400X0400Y0500R180 S1      
327GND              PC36  -2          A01X+062250Y+019650X0400Y0500R180 S1      
327GND              PC38  -2          A01X+060100Y+020400X0400Y0500R180 S1      
327GND              PC39  -2          A01X+060100Y+019650X0400Y0500R180 S1      
327GND              PC64  -2          A01X+042250Y+020450X0400Y0500R180 S1      
327GND              PC65  -2          A01X+042250Y+019700X0400Y0500R180 S1      
327GND              PC66  -2          A01X+040100Y+020450X0400Y0500R180 S1      
327GND              PC67  -2          A01X+040100Y+019700X0400Y0500R180 S1      
327GND              PC87  -2          A01X+037950Y+019700X0400Y0500R180 S1      
327GND              PC86  -2          A01X+037950Y+020450X0400Y0500R180 S1      
327GND              PC89  -2          A01X+035800Y+019650X0400Y0500R180 S1      
327GND              PC88  -2          A01X+035800Y+020450X0400Y0500R180 S1      
327GND              PC91  -2          A01X+033650Y+019650X0400Y0500R180 S1      
327GND              PC90  -2          A01X+033650Y+020450X0400Y0500R180 S1      
327GND              PC92  -2          A01X+031500Y+020450X0400Y0500R180 S1      
327GND              PC93  -2          A01X+031500Y+019650X0400Y0500R180 S1      
327GND              PC95  -2          A01X+029350Y+019650X0400Y0500R180 S1      
327GND              PC94  -2          A01X+029350Y+020450X0400Y0500R180 S1      
327GND              C45   -2          A01X+095200Y+037020X0460Y0620R090 S1      
327GND              C43   -2          A01X+094250Y+037020X0460Y0620R090 S1      
327GND              C39   -2          A01X+092350Y+037020X0460Y0620R090 S1      
327GND              C37   -2          A01X+091400Y+037020X0460Y0620R090 S1      
327GND              C35   -2          A01X+090450Y+037020X0460Y0620R090 S1      
327GND              C41   -2          A01X+093300Y+037020X0460Y0620R090 S1      
327GND              C33   -2          A01X+089500Y+037020X0460Y0620R090 S1      
327GND              C31   -2          A01X+088550Y+037020X0460Y0620R090 S1      
327GND              C29   -2          A01X+087600Y+037020X0460Y0620R090 S1      
327GND              C25   -2          A01X+085800Y+037020X0460Y0620R090 S1      
327GND              C27   -2          A01X+086700Y+037020X0460Y0620R090 S1      
327GND              C23   -2          A01X+084900Y+037020X0460Y0620R090 S1      
327GND              PC75  -2          A01X+018184Y+051250X0460Y0620R180 S1      
327GND              PC74  -2          A01X+018184Y+050350X0460Y0620R180 S1      
327GND              PC77  -2          A01X+022984Y+050350X0460Y0620R180 S1      
327GND              PC76  -2          A01X+022984Y+051250X0460Y0620R180 S1      
327GND              PC79  -2          A01X+027784Y+051250X0460Y0620R180 S1      
327GND              PC78  -2          A01X+027784Y+050350X0460Y0620R180 S1      
327GND              PC51  -2          A01X+033932Y+051250X0460Y0620R180 S1      
327GND              PC50  -2          A01X+033932Y+050350X0460Y0620R180 S1      
327GND              PC49  -2          A01X+038732Y+050350X0460Y0620R180 S1      
327GND              PC48  -2          A01X+038732Y+051250X0460Y0620R180 S1      
327GND              PC47  -2          A01X+043532Y+051250X0460Y0620R180 S1      
327GND              PC46  -2          A01X+043532Y+050350X0460Y0620R180 S1      
327GND              PC23  -2          A01X+049680Y+050350X0460Y0620R180 S1      
327GND              PC22  -2          A01X+049680Y+051250X0460Y0620R180 S1      
327GND              PC21  -2          A01X+054480Y+051250X0460Y0620R180 S1      
327GND              PC20  -2          A01X+054480Y+050350X0460Y0620R180 S1      
327GND              PC19  -2          A01X+059280Y+050350X0460Y0620R180 S1      
327GND              PC18  -2          A01X+059280Y+051250X0460Y0620R180 S1      
327GND              PC121 -2          A01X+065428Y+050350X0460Y0620R180 S1      
327GND              PC120 -2          A01X+065428Y+051250X0460Y0620R180 S1      
327GND              PC118 -2          A01X+070228Y+050350X0460Y0620R180 S1      
327GND              PC117 -2          A01X+070228Y+051250X0460Y0620R180 S1      
327GND              PC112 -2          A01X+075608Y+006850X0198Y0197     S1      
327GND              PC104 -2          A01X+075608Y+002750X0198Y0197     S1      
327GND              D4    -A          A01X+019740Y+023335X0850Y0890R270 S1      
317GND              PC72  -2   MD0420PA00X+023322Y+053900X0620Y         S3      
317GND              PC73  -2   MD0420PA00X+018522Y+053900X0620Y         S3      
317GND              VIA   -    MD0100PA00X+020176Y+024510X0200Y         S0      
317GND              VIA   -    MD0100PA00X+020176Y+024210X0200Y         S0      
317GND              VIA   -    MD0100PA00X+019876Y+024510X0200Y         S0      
317GND              VIA   -    MD0100PA00X+019876Y+024210X0200Y         S0      
317GND              VIA   -    MD0100PA00X+019576Y+024510X0200Y         S0      
317GND              VIA   -    MD0100PA00X+019576Y+024210X0200Y         S0      
317GND              VIA   -    MD0100PA00X+019276Y+024510X0200Y         S0      
317GND              VIA   -    MD0100PA00X+019276Y+024210X0200Y         S0      
317GND              VIA   -    MD0100PA00X+018976Y+024510X0200Y         S0      
317GND              VIA   -    MD0100PA00X+018976Y+024210X0200Y         S0      
327GND              D2    -C          A01X+079785Y+026224X0240Y0280R270 S1      
317GND              VIA   -    MD0100PA00X+079785Y+025954X0200Y         S0      
327GND              D3    -C          A01X+080950Y+026213X0240Y0280R270 S1      
317GND              VIA   -    MD0100PA00X+080950Y+025943X0200Y         S0      
317GND              VIA   -    MD0100PA00X+093150Y+036600X0200Y         S0      
317GND              VIA   -    MD0100PA00X+095350Y+036600X0200Y         S0      
317GND              VIA   -    MD0100PA00X+095050Y+036600X0200Y         S0      
317GND              VIA   -    MD0100PA00X+093450Y+036600X0200Y         S0      
317GND              VIA   -    MD0100PA00X+094100Y+036600X0200Y         S0      
317GND              VIA   -    MD0100PA00X+094400Y+036600X0200Y         S0      
317GND              VIA   -    MD0100PA00X+092500Y+036600X0200Y         S0      
317GND              VIA   -    MD0100PA00X+092200Y+036600X0200Y         S0      
317GND              VIA   -    MD0100PA00X+091550Y+036600X0200Y         S0      
317GND              VIA   -    MD0100PA00X+091250Y+036600X0200Y         S0      
317GND              VIA   -    MD0100PA00X+090300Y+036600X0200Y         S0      
317GND              VIA   -    MD0100PA00X+090600Y+036600X0200Y         S0      
317GND              VIA   -    MD0100PA00X+086850Y+036600X0200Y         S0      
317GND              VIA   -    MD0100PA00X+089650Y+036600X0200Y         S0      
317GND              VIA   -    MD0100PA00X+089350Y+036600X0200Y         S0      
317GND              VIA   -    MD0100PA00X+088700Y+036600X0200Y         S0      
317GND              VIA   -    MD0100PA00X+088400Y+036600X0200Y         S0      
317GND              VIA   -    MD0100PA00X+087450Y+036600X0200Y         S0      
317GND              VIA   -    MD0100PA00X+087750Y+036600X0200Y         S0      
317GND              VIA   -    MD0100PA00X+086550Y+036600X0200Y         S0      
317GND              VIA   -    MD0100PA00X+085950Y+036600X0200Y         S0      
317GND              VIA   -    MD0100PA00X+085650Y+036600X0200Y         S0      
317GND              VIA   -    MD0100PA00X+084750Y+036600X0200Y         S0      
317GND              VIA   -    MD0100PA00X+085050Y+036600X0200Y         S0      
317GND              VIA   -    MD0100PA00X+069626Y+044502X0200Y         S0      
327GND              C70   -2          A10X+069626Y+044742X0198Y0197R090 S2      
327GND              C74   -1          A10X+043202Y+045442X0198Y0197R270 S2      
317GND              VIA   -    MD0100PA00X+043202Y+045202X0200Y         S0      
327GND              U24   -S          A10X+042646Y+044426X0320Y0360R090 S2      
317GND              VIA   -    MD0100PA00X+043002Y+044426X0200Y         S0      
327GND              PC110 -1          A01X+070146Y+003670X0198Y0197     S1      
327GND              PR91  -2          A01X+069761Y+003670X0198Y0197     S1      
327GND              PU5   -7          A01X+070098Y+004159X0098Y0276     S1      
327GND              PC109 -2          A01X+069852Y+005780X0198Y0197R180 S1      
327GND              PU5   -14         A01X+069902Y+005301X0098Y0276R180 S1      
327GND              PU5   -1          A01X+069626Y+005124X0098Y0276R270 S1      
327GND              PC101 -2          A01X+067740Y+005270X0400Y0500R270 S1      
327GND              PC100 -2          A01X+068530Y+005270X0400Y0500R270 S1      
327GND              PC108 -2          A01X+075800Y+006000X0400Y0500R180 S1      
327GND              PC107 -2          A01X+075800Y+005150X0400Y0500R180 S1      
327GND              PC106 -2          A01X+075800Y+004300X0400Y0500R180 S1      
327GND              PC105 -2          A01X+075800Y+003450X0400Y0500R180 S1      
327GND              PR88  -2          A01X+070600Y+005958X0198Y0197R090 S1      
327GND              R83   -2          A01X+068692Y+003250X0198Y0197R180 S1      
327GND              PR89  -2          A01X+068692Y+003650X0198Y0197R180 S1      
317GND              VIA   -    MD0100PA00X+068650Y+005680X0200Y         S0      
317GND              VIA   -    M      A01X+067600Y+005680X0200Y         S2      
017GND              VIA   -    M      A10X+067600Y+005680X0260Y         S2      
017GND                    -    MD0100PA00X+067600Y+005680                       
317GND              VIA   -    MD0100PA00X+067900Y+005680X0200Y         S0      
317GND              VIA   -    M      A01X+068360Y+005680X0200Y         S2      
017GND              VIA   -    M      A10X+068360Y+005680X0260Y         S2      
017GND                    -    MD0100PA00X+068360Y+005680                       
317GND              VIA   -    MD0100PA00X+068452Y+003650X0200Y         S0      
317GND              VIA   -    M      A01X+068452Y+003250X0200Y         S2      
017GND              VIA   -    M      A10X+068452Y+003250X0260Y         S2      
017GND                    -    MD0100PA00X+068452Y+003250                       
317GND              VIA   -    M      A01X+070600Y+006198X0200Y         S2      
017GND              VIA   -    M      A10X+070600Y+006198X0260Y         S2      
017GND                    -    MD0100PA00X+070600Y+006198                       
317GND              VIA   -    MD0100PA00X+069950Y+003450X0200Y         S0      
317GND              VIA   -    MD0100PA00X+069610Y+005670X0200Y         S0      
317GND              VIA   -    M      A01X+069300Y+005660X0200Y         S2      
017GND              VIA   -    M      A10X+069300Y+005660X0260Y         S2      
017GND                    -    MD0100PA00X+069300Y+005660                       
317GND              VIA   -    MD0100PA00X+068990Y+005660X0200Y         S0      
317GND              VIA   -    MD0100PA00X+069140Y+005330X0200Y         S0      
317GND              VIA   -    MD0100PA00X+069420Y+005330X0200Y         S0      
317GND              VIA   -    MD0100PA00X+069690Y+005330X0200Y         S0      
317GND              VIA   -    MD0100PA00X+075616Y+006400X0200Y         S0      
317GND              VIA   -    MD0100PA00X+075876Y+006400X0200Y         S0      
317GND              VIA   -    M      A01X+076156Y+006400X0200Y         S2      
017GND              VIA   -    M      A10X+076156Y+006400X0260Y         S2      
017GND                    -    MD0100PA00X+076156Y+006400                       
317GND              VIA   -    MD0100PA00X+075890Y+002740X0200Y         S0      
317GND              VIA   -    MD0100PA00X+075616Y+003000X0200Y         S0      
317GND              VIA   -    MD0100PA00X+075876Y+003000X0200Y         S0      
317GND              VIA   -    M      A01X+076156Y+003000X0200Y         S2      
017GND              VIA   -    M      A10X+076156Y+003000X0260Y         S2      
017GND                    -    MD0100PA00X+076156Y+003000                       
317GND              VIA   -    MD0100PA00X+075616Y+003850X0200Y         S0      
317GND              VIA   -    MD0100PA00X+075876Y+003850X0200Y         S0      
317GND              VIA   -    M      A01X+076156Y+003850X0200Y         S2      
017GND              VIA   -    M      A10X+076156Y+003850X0260Y         S2      
017GND                    -    MD0100PA00X+076156Y+003850                       
317GND              VIA   -    MD0100PA00X+075616Y+004700X0200Y         S0      
317GND              VIA   -    MD0100PA00X+075876Y+004700X0200Y         S0      
317GND              VIA   -    M      A01X+076156Y+004700X0200Y         S2      
017GND              VIA   -    M      A10X+076156Y+004700X0260Y         S2      
017GND                    -    MD0100PA00X+076156Y+004700                       
317GND              VIA   -    MD0100PA00X+075616Y+005550X0200Y         S0      
317GND              VIA   -    MD0100PA00X+075876Y+005550X0200Y         S0      
317GND              VIA   -    M      A01X+076156Y+005550X0200Y         S2      
017GND              VIA   -    M      A10X+076156Y+005550X0260Y         S2      
017GND                    -    MD0100PA00X+076156Y+005550                       
327GND              PR325 -2          A10X+023957Y+030358X0198Y0197R270 S2      
317GND              H14   -1   MD1190PA00X+098850Y+022800X3940Y    R270 S3      
317GND              PC71  -2   MD0420PA00X+028122Y+053900X0620Y         S3      
317GND              PC96  -2   MD0400PA00X+035700Y+022032X0600Y    R270 S3      
317GND              PC97  -2   MD0400PA00X+031250Y+022032X0600Y    R270 S3      
317GND              PC98  -2   MD0400PA00X+026800Y+022032X0600Y    R270 S3      
317GND              PC43  -2   MD0420PA00X+043870Y+053900X0620Y         S3      
317GND              PC44  -2   MD0420PA00X+039070Y+053900X0620Y         S3      
317GND              PC45  -2   MD0420PA00X+034270Y+053900X0620Y         S3      
317GND              PC68  -2   MD0400PA00X+042850Y+022032X0600Y    R270 S3      
317GND              PC69  -2   MD0400PA00X+051650Y+022032X0600Y    R270 S3      
317GND              PC70  -2   MD0400PA00X+047250Y+022032X0600Y    R270 S3      
317GND              PC15  -2   MD0420PA00X+059618Y+053900X0620Y         S3      
317GND              PC16  -2   MD0420PA00X+054818Y+053900X0620Y         S3      
317GND              PC17  -2   MD0420PA00X+050018Y+053900X0620Y         S3      
317GND              PC40  -2   MD0400PA00X+057850Y+022032X0600Y    R270 S3      
317GND              PC41  -2   MD0400PA00X+066650Y+022032X0600Y    R270 S3      
317GND              PC42  -2   MD0400PA00X+062250Y+022032X0600Y    R270 S3      
317GND              PC114 -2   MD0420PA00X+070567Y+053900X0620Y         S3      
317GND              PC134 -2   MD0400PA00X+082398Y+022032X0600Y    R270 S3      
317GND              PC135 -2   MD0400PA00X+077998Y+022032X0600Y    R270 S3      
317GND              PC136 -2   MD0400PA00X+073598Y+022032X0600Y    R270 S3      
317GND              VIA   -    MD0100PA00X+070000Y+030550X0200Y         S0      
327GND              C72   -2          A10X+069756Y+030550X0198Y0197R180 S2      
317GND              VIA   -    M      A01X+075198Y+051800X0200Y         S2      
017GND              VIA   -    M      A10X+075198Y+051800X0260Y         S2      
017GND                    -    MD0100PA00X+075198Y+051800                       
317GND              VIA   -    MD0100PA00X+074898Y+051800X0200Y         S0      
317GND              VIA   -    M      A01X+075198Y+049800X0200Y    R180 S2      
017GND              VIA   -    M      A10X+075198Y+049800X0260Y    R180 S2      
017GND                    -    MD0100PA00X+075198Y+049800                       
317GND              VIA   -    MD0100PA00X+074898Y+049800X0200Y    R180 S0      
327GND              PC116 -2          A01X+075028Y+051250X0460Y0620R180 S1      
327GND              PC119 -2          A01X+075028Y+050350X0460Y0620R180 S1      
317GND              VIA   -    MD0100PA00X+070098Y+049800X0200Y    R180 S0      
317GND              VIA   -    M      A01X+070398Y+049800X0200Y    R180 S2      
017GND              VIA   -    M      A10X+070398Y+049800X0260Y    R180 S2      
017GND                    -    MD0100PA00X+070398Y+049800                       
317GND              VIA   -    MD0100PA00X+070098Y+051800X0200Y         S0      
317GND              VIA   -    M      A01X+070398Y+051800X0200Y         S2      
017GND              VIA   -    M      A10X+070398Y+051800X0260Y         S2      
017GND                    -    MD0100PA00X+070398Y+051800                       
317GND              VIA   -    MD0100PA00X+065298Y+049800X0200Y    R180 S0      
317GND              VIA   -    M      A01X+065598Y+049800X0200Y    R180 S2      
017GND              VIA   -    M      A10X+065598Y+049800X0260Y    R180 S2      
017GND                    -    MD0100PA00X+065598Y+049800                       
317GND              VIA   -    MD0100PA00X+065298Y+051800X0200Y         S0      
317GND              VIA   -    M      A01X+065598Y+051800X0200Y         S2      
017GND              VIA   -    M      A10X+065598Y+051800X0260Y         S2      
017GND                    -    MD0100PA00X+065598Y+051800                       
317GND              VIA   -    MD0100PA00X+071298Y+023900X0200Y         S0      
317GND              VIA   -    MD0100PA00X+071298Y+023600X0200Y         S0      
317GND              VIA   -    MD0100PA00X+070948Y+024350X0200Y         S0      
317GND              VIA   -    MD0100PA00X+070950Y+024700X0200Y         S0      
317GND              VIA   -    MD0100PA00X+069096Y+030550X0200Y         S0      
317GND              VIA   -    MD0100PA00X+070896Y+030550X0200Y         S0      
327GND              PR319 -2          A10X+068051Y+030358X0198Y0197R270 S2      
317GND              VIA   -    MD0100PA00X+068051Y+030598X0200Y         S0      
327GND              PR320 -1          A10X+071201Y+030358X0198Y0197R090 S2      
317GND              VIA   -    MD0100PA00X+071201Y+030598X0200Y         S0      
317GND              PU6   -3   MD0630PA00X+066626Y+047720X0930Y    R270 S3      
317GND              PU6   -4   MD0830PA00X+065126Y+027720X1230Y    R270 S3      
317GND              PU6   -5   MD0830PA00X+066626Y+027720X1230Y    R270 S3      
317GND              VIA   -    MD0100PA00X+054506Y+034034X0200Y         S0      
317GND              VIA   -    MD0100PA00X+047310Y+034034X0200Y         S0      
317GND              VIA   -    MD0100PA00X+044726Y+034034X0200Y         S0      
317GND              VIA   -    MD0100PA00X+031357Y+034055X0200Y         S0      
317GND              VIA   -    MD0100PA00X+029072Y+034034X0200Y         S0      
317GND              VIA   -    MD0100PA00X+017326Y+034055X0200Y         S0      
317GND              VIA   -    MD0100PA00X+113017Y+003858X0200Y    R090 S0      
317GND              VIA   -    MD0100PA00X+113267Y+003858X0200Y    R090 S0      
317GND              VIA   -    MD0100PA00X+113517Y+003858X0200Y    R090 S0      
317GND              VIA   -    MD0100PA00X+113517Y+003558X0200Y    R090 S0      
317GND              VIA   -    MD0100PA00X+113267Y+003558X0200Y    R090 S0      
317GND              VIA   -    MD0100PA00X+113017Y+003558X0200Y    R090 S0      
317GND              VIA   -    MD0100PA00X+112767Y+003558X0200Y    R090 S0      
317GND              VIA   -    MD0100PA00X+112767Y+003858X0200Y    R090 S0      
317GND              VIA   -    MD0100PA00X+112517Y+003858X0200Y    R090 S0      
317GND              VIA   -    MD0100PA00X+112517Y+003558X0200Y    R090 S0      
317GND              VIA   -    MD0100PA00X+113795Y+008587X0200Y    R090 S0      
317GND              VIA   -    MD0100PA00X+114045Y+008587X0200Y    R090 S0      
317GND              VIA   -    MD0100PA00X+114295Y+008587X0200Y    R090 S0      
317GND              VIA   -    MD0100PA00X+114295Y+008287X0200Y    R090 S0      
317GND              VIA   -    MD0100PA00X+114045Y+008287X0200Y    R090 S0      
317GND              VIA   -    MD0100PA00X+113795Y+008287X0200Y    R090 S0      
317GND              VIA   -    MD0100PA00X+113545Y+008287X0200Y    R090 S0      
317GND              VIA   -    MD0100PA00X+113545Y+008587X0200Y    R090 S0      
317GND              VIA   -    MD0100PA00X+113295Y+008587X0200Y    R090 S0      
317GND              VIA   -    MD0100PA00X+113295Y+008287X0200Y    R090 S0      
327GND              PD6   -A          A10X+118356Y+013047X0950Y1300R090 S2      
317GND              H19   -1   M      A01X+124016Y+052126X4000Y    R270 S3      
017GND              H19   -1   M      A10X+124016Y+052126X3940Y    R270 S3      
017GND                    -    MD2520PA00X+124016Y+052126                       
317GND              VIA   -    MD0100PA00X+117950Y+010550X0200Y         S0      
327GND              C69   -2   M      A01X+117640Y+010550X0280Y0320R270 S1      
317GND              VIA   -    MD0100PA00X+117748Y+011150X0200Y         S0      
327GND              U23   -S          A10X+058394Y+044426X0320Y0360R090 S2      
327GND              C51   -2          A10X+053878Y+044742X0198Y0197R090 S2      
327GND              C56   -2          A10X+038130Y+044742X0198Y0197R090 S2      
327GND              C60   -2          A10X+022382Y+044742X0198Y0197R090 S2      
327GND              C54   -2          A10X+054908Y+030550X0198Y0197R180 S2      
327GND              C53   -2          A10X+054008Y+030550X0198Y0197R180 S2      
327GND              C52   -2          A10X+053108Y+030550X0198Y0197R180 S2      
327GND              C57   -2          A10X+039058Y+030500X0198Y0197R180 S2      
327GND              C59   -2          A10X+038158Y+030500X0198Y0197R180 S2      
327GND              C58   -2          A10X+037308Y+030500X0198Y0197R180 S2      
327GND              C63   -2          A10X+023358Y+030500X0198Y0197R180 S2      
327GND              C62   -2          A10X+022458Y+030500X0198Y0197R180 S2      
327GND              C61   -2          A10X+021608Y+030500X0198Y0197R180 S2      
327GND              PR79  -2          A10X+020807Y+030358X0198Y0197R270 S2      
327GND              PR67  -2          A10X+036555Y+030358X0198Y0197R270 S2      
327GND              PR73  -1          A10X+039705Y+030358X0198Y0197R090 S2      
327GND              PR52  -2          A10X+052303Y+030358X0198Y0197R270 S2      
327GND              PR58  -1          A10X+055453Y+030358X0198Y0197R090 S2      
317GND              VIA   -    MD0100PA00X+117832Y+012065X0200Y    R090 S0      
317GND              VIA   -    MD0100PA00X+117832Y+012365X0200Y    R090 S0      
317GND              VIA   -    MD0100PA00X+118082Y+012365X0200Y    R090 S0      
317GND              VIA   -    MD0100PA00X+118082Y+012065X0200Y    R090 S0      
317GND              VIA   -    MD0100PA00X+127944Y+057381X0200Y         S0      
317GND              VIA   -    MD0100PA00X+111145Y+054700X0200Y    R270 S0      
317GND              VIA   -    MD0100PA00X+111445Y+054700X0200Y    R270 S0      
317GND              VIA   -    MD0100PA00X+111145Y+055000X0200Y    R270 S0      
317GND              VIA   -    MD0100PA00X+111445Y+055000X0200Y    R270 S0      
317GND              VIA   -    MD0100PA00X+111145Y+055300X0200Y    R270 S0      
317GND              VIA   -    M      A01X+111445Y+055300X0200Y    R270 S2      
017GND              VIA   -    M      A10X+111445Y+055300X0260Y    R270 S2      
017GND                    -    MD0100PA00X+111445Y+055300                       
317GND              VIA   -    MD0100PA00X+111145Y+053800X0200Y    R270 S0      
317GND              VIA   -    M      A01X+111445Y+053800X0200Y    R270 S2      
017GND              VIA   -    M      A10X+111445Y+053800X0260Y    R270 S2      
017GND                    -    MD0100PA00X+111445Y+053800                       
317GND              VIA   -    MD0100PA00X+111445Y+054100X0200Y    R270 S0      
317GND              VIA   -    MD0100PA00X+111445Y+054400X0200Y    R270 S0      
317GND              VIA   -    MD0100PA00X+111145Y+054100X0200Y    R270 S0      
317GND              VIA   -    MD0100PA00X+111145Y+054400X0200Y    R270 S0      
317GND              VIA   -    MD0100PA00X+058750Y+044426X0200Y         S0      
317GND              VIA   -    MD0100PA00X+000454Y+056600X0200Y         S0      
317GND              VIA   -    MD0100PA00X+000302Y+054931X0200Y         S0      
317GND              VIA   -    MD0100PA00X+000302Y+052431X0200Y         S0      
317GND              VIA   -    MD0100PA00X+000991Y+051003X0200Y         S0      
317GND              VIA   -    MD0100PA00X+003955Y+045492X0200Y         S0      
317GND              VIA   -    MD0100PA00X+001956Y+045459X0200Y         S0      
317GND              VIA   -    MD0100PA00X+000300Y+044524X0200Y         S0      
317GND              VIA   -    MD0100PA00X+000300Y+042524X0200Y         S0      
317GND              VIA   -    MD0100PA00X+000300Y+040524X0200Y         S0      
317GND              VIA   -    MD0100PA00X+000300Y+038524X0200Y         S0      
317GND              VIA   -    MD0100PA00X+000300Y+036524X0200Y         S0      
317GND              VIA   -    MD0100PA00X+000300Y+034524X0200Y         S0      
317GND              VIA   -    MD0100PA00X+000300Y+032524X0200Y         S0      
317GND              VIA   -    MD0100PA00X+000300Y+030524X0200Y         S0      
317GND              VIA   -    MD0100PA00X+000300Y+028524X0200Y         S0      
317GND              VIA   -    MD0100PA00X+000300Y+026524X0200Y         S0      
317GND              VIA   -    MD0100PA00X+000300Y+024524X0200Y         S0      
317GND              VIA   -    MD0100PA00X+000300Y+022524X0200Y         S0      
317GND              VIA   -    MD0100PA00X+000300Y+020524X0200Y         S0      
317GND              VIA   -    MD0100PA00X+000300Y+018524X0200Y         S0      
317GND              VIA   -    MD0100PA00X+000300Y+016524X0200Y         S0      
317GND              VIA   -    MD0100PA00X+000300Y+014524X0200Y         S0      
317GND              VIA   -    MD0100PA00X+000760Y+012837X0200Y         S0      
317GND              VIA   -    MD0100PA00X+002727Y+012730X0200Y         S0      
317GND              VIA   -    MD0100PA00X+001277Y+007207X0200Y         S0      
317GND              VIA   -    MD0100PA00X+000300Y+005981X0200Y         S0      
317GND              VIA   -    MD0100PA00X+000300Y+003481X0200Y         S0      
317GND              VIA   -    MD0100PA00X+000300Y+001981X0200Y         S0      
317GND              VIA   -    MD0100PA00X+001481Y+000373X0200Y         S0      
317GND              VIA   -    MD0100PA00X+003458Y+000300X0200Y         S0      
317GND              VIA   -    MD0100PA00X+005458Y+000300X0200Y         S0      
317GND              VIA   -    MD0100PA00X+007458Y+000300X0200Y         S0      
317GND              VIA   -    MD0100PA00X+009458Y+000300X0200Y         S0      
317GND              VIA   -    MD0100PA00X+011458Y+000300X0200Y         S0      
317GND              VIA   -    MD0100PA00X+013458Y+000300X0200Y         S0      
317GND              VIA   -    MD0100PA00X+015458Y+000300X0200Y         S0      
317GND              VIA   -    MD0100PA00X+017458Y+000300X0200Y         S0      
317GND              VIA   -    MD0100PA00X+019458Y+000300X0200Y         S0      
317GND              VIA   -    MD0100PA00X+021458Y+000300X0200Y         S0      
317GND              VIA   -    MD0100PA00X+023458Y+000300X0200Y         S0      
317GND              VIA   -    MD0100PA00X+025458Y+000300X0200Y         S0      
317GND              VIA   -    MD0100PA00X+027458Y+000300X0200Y         S0      
317GND              VIA   -    MD0100PA00X+029458Y+000300X0200Y         S0      
317GND              VIA   -    MD0100PA00X+031458Y+000300X0200Y         S0      
317GND              VIA   -    MD0100PA00X+033458Y+000300X0200Y         S0      
317GND              VIA   -    MD0100PA00X+035458Y+000300X0200Y         S0      
317GND              VIA   -    MD0100PA00X+037458Y+000300X0200Y         S0      
317GND              VIA   -    MD0100PA00X+039458Y+000300X0200Y         S0      
317GND              VIA   -    MD0100PA00X+041458Y+000300X0200Y         S0      
317GND              VIA   -    MD0100PA00X+043458Y+000300X0200Y         S0      
317GND              VIA   -    MD0100PA00X+045458Y+000300X0200Y         S0      
317GND              VIA   -    MD0100PA00X+047458Y+000300X0200Y         S0      
317GND              VIA   -    MD0100PA00X+049458Y+000300X0200Y         S0      
317GND              VIA   -    MD0100PA00X+051458Y+000300X0200Y         S0      
317GND              VIA   -    MD0100PA00X+053458Y+000300X0200Y         S0      
317GND              VIA   -    MD0100PA00X+055458Y+000300X0200Y         S0      
317GND              VIA   -    MD0100PA00X+057458Y+000300X0200Y         S0      
317GND              VIA   -    MD0100PA00X+059458Y+000300X0200Y         S0      
317GND              VIA   -    MD0100PA00X+061458Y+000300X0200Y         S0      
317GND              VIA   -    MD0100PA00X+063458Y+000300X0200Y         S0      
317GND              VIA   -    MD0100PA00X+065458Y+000300X0200Y         S0      
317GND              VIA   -    MD0100PA00X+067458Y+000300X0200Y         S0      
317GND              VIA   -    MD0100PA00X+069458Y+000300X0200Y         S0      
317GND              VIA   -    MD0100PA00X+071458Y+000300X0200Y         S0      
317GND              VIA   -    MD0100PA00X+073458Y+000300X0200Y         S0      
317GND              VIA   -    MD0100PA00X+075458Y+000300X0200Y         S0      
317GND              VIA   -    MD0100PA00X+077458Y+000300X0200Y         S0      
317GND              VIA   -    MD0100PA00X+079458Y+000300X0200Y         S0      
317GND              VIA   -    MD0100PA00X+081458Y+000300X0200Y         S0      
317GND              VIA   -    MD0100PA00X+083458Y+000300X0200Y         S0      
317GND              VIA   -    MD0100PA00X+085458Y+000300X0200Y         S0      
317GND              VIA   -    MD0100PA00X+087458Y+000300X0200Y         S0      
317GND              VIA   -    MD0100PA00X+089458Y+000300X0200Y         S0      
317GND              VIA   -    MD0100PA00X+091458Y+000300X0200Y         S0      
317GND              VIA   -    MD0100PA00X+093458Y+000300X0200Y         S0      
317GND              VIA   -    MD0100PA00X+095458Y+000300X0200Y         S0      
317GND              VIA   -    MD0100PA00X+097458Y+000300X0200Y         S0      
317GND              VIA   -    MD0100PA00X+099458Y+000300X0200Y         S0      
317GND              VIA   -    MD0100PA00X+101458Y+000300X0200Y         S0      
317GND              VIA   -    MD0100PA00X+103458Y+000300X0200Y         S0      
317GND              VIA   -    MD0100PA00X+105458Y+000300X0200Y         S0      
317GND              VIA   -    MD0100PA00X+107458Y+000300X0200Y         S0      
317GND              VIA   -    MD0100PA00X+109458Y+000300X0200Y         S0      
317GND              VIA   -    MD0100PA00X+111458Y+000300X0200Y         S0      
317GND              VIA   -    MD0100PA00X+113458Y+000300X0200Y         S0      
317GND              VIA   -    MD0100PA00X+115458Y+000300X0200Y         S0      
317GND              VIA   -    MD0100PA00X+117458Y+000300X0200Y         S0      
317GND              VIA   -    MD0100PA00X+119458Y+000300X0200Y         S0      
317GND              VIA   -    MD0100PA00X+121458Y+000300X0200Y         S0      
317GND              VIA   -    MD0100PA00X+123458Y+000300X0200Y         S0      
317GND              VIA   -    MD0100PA00X+125458Y+000300X0200Y         S0      
317GND              VIA   -    MD0100PA00X+127766Y+000413X0200Y         S0      
317GND              VIA   -    MD0100PA00X+128677Y+001263X0200Y         S0      
317GND              VIA   -    MD0100PA00X+128833Y+003096X0200Y         S0      
317GND              VIA   -    MD0100PA00X+128833Y+005096X0200Y         S0      
317GND              VIA   -    MD0100PA00X+128833Y+007096X0200Y         S0      
317GND              VIA   -    MD0100PA00X+128833Y+009096X0200Y         S0      
317GND              VIA   -    MD0100PA00X+128833Y+011096X0200Y         S0      
317GND              VIA   -    MD0100PA00X+128833Y+013096X0200Y         S0      
317GND              VIA   -    MD0100PA00X+128833Y+015096X0200Y         S0      
317GND              VIA   -    MD0100PA00X+128833Y+017096X0200Y         S0      
317GND              VIA   -    MD0100PA00X+128833Y+019096X0200Y         S0      
317GND              VIA   -    MD0100PA00X+128833Y+021096X0200Y         S0      
317GND              VIA   -    MD0100PA00X+128833Y+023096X0200Y         S0      
317GND              VIA   -    MD0100PA00X+128833Y+025096X0200Y         S0      
317GND              VIA   -    MD0100PA00X+128833Y+027096X0200Y         S0      
317GND              VIA   -    MD0100PA00X+128833Y+029096X0200Y         S0      
317GND              VIA   -    MD0100PA00X+128833Y+031096X0200Y         S0      
317GND              VIA   -    MD0100PA00X+128833Y+033096X0200Y         S0      
317GND              VIA   -    MD0100PA00X+128833Y+035096X0200Y         S0      
317GND              VIA   -    MD0100PA00X+128833Y+037096X0200Y         S0      
317GND              VIA   -    MD0100PA00X+128833Y+039096X0200Y         S0      
317GND              VIA   -    MD0100PA00X+128833Y+041096X0200Y         S0      
317GND              VIA   -    MD0100PA00X+128833Y+043096X0200Y         S0      
317GND              VIA   -    MD0100PA00X+128833Y+045096X0200Y         S0      
317GND              VIA   -    MD0100PA00X+128833Y+047096X0200Y         S0      
317GND              VIA   -    MD0100PA00X+128833Y+049096X0200Y         S0      
317GND              VIA   -    MD0100PA00X+128833Y+051096X0200Y         S0      
317GND              VIA   -    MD0100PA00X+128833Y+053096X0200Y         S0      
317GND              VIA   -    MD0100PA00X+128833Y+055096X0200Y         S0      
317GND              VIA   -    MD0100PA00X+128762Y+056389X0200Y         S0      
317GND              VIA   -    MD0100PA00X+126050Y+057574X0200Y         S0      
317GND              VIA   -    MD0100PA00X+124050Y+057574X0200Y         S0      
317GND              VIA   -    MD0100PA00X+122050Y+057574X0200Y         S0      
317GND              VIA   -    MD0100PA00X+120050Y+057574X0200Y         S0      
317GND              VIA   -    MD0100PA00X+118050Y+057574X0200Y         S0      
317GND              VIA   -    MD0100PA00X+116050Y+057574X0200Y         S0      
317GND              VIA   -    MD0100PA00X+114050Y+057574X0200Y         S0      
317GND              VIA   -    MD0100PA00X+112050Y+057574X0200Y         S0      
317GND              VIA   -    MD0100PA00X+110050Y+057574X0200Y         S0      
317GND              VIA   -    MD0100PA00X+108050Y+057574X0200Y         S0      
317GND              VIA   -    MD0100PA00X+106050Y+057574X0200Y         S0      
317GND              VIA   -    MD0100PA00X+104050Y+057574X0200Y         S0      
317GND              VIA   -    MD0100PA00X+102050Y+057574X0200Y         S0      
317GND              VIA   -    MD0100PA00X+100050Y+057574X0200Y         S0      
317GND              VIA   -    MD0100PA00X+098050Y+057574X0200Y         S0      
317GND              VIA   -    MD0100PA00X+096050Y+057574X0200Y         S0      
317GND              VIA   -    MD0100PA00X+094050Y+057574X0200Y         S0      
317GND              VIA   -    MD0100PA00X+014050Y+057574X0200Y         S0      
317GND              VIA   -    MD0100PA00X+012050Y+057574X0200Y         S0      
317GND              VIA   -    MD0100PA00X+010050Y+057574X0200Y         S0      
317GND              VIA   -    MD0100PA00X+008050Y+057574X0200Y         S0      
317GND              VIA   -    MD0100PA00X+006050Y+057574X0200Y         S0      
317GND              VIA   -    MD0100PA00X+004050Y+057574X0200Y         S0      
317GND              VIA   -    MD0100PA00X+002050Y+057574X0200Y         S0      
317GND              H2    -1   MD1190PA00X+103050Y+054250X3940Y    R270 S3      
317GND              H11   -1   MD1190PA00X+011811Y+053543X3940Y    R270 S3      
317GND              VIA   -    MD0100PA00X+059150Y+051800X0200Y         S0      
317GND              VIA   -    M      A01X+059450Y+051800X0200Y         S2      
017GND              VIA   -    M      A10X+059450Y+051800X0260Y         S2      
017GND                    -    MD0100PA00X+059450Y+051800                       
317GND              VIA   -    MD0100PA00X+059150Y+049800X0200Y    R180 S0      
317GND              VIA   -    M      A01X+059450Y+049800X0200Y    R180 S2      
017GND              VIA   -    M      A10X+059450Y+049800X0260Y    R180 S2      
017GND                    -    MD0100PA00X+059450Y+049800                       
317GND              VIA   -    M      A01X+054650Y+051800X0200Y         S2      
017GND              VIA   -    M      A10X+054650Y+051800X0260Y         S2      
017GND                    -    MD0100PA00X+054650Y+051800                       
317GND              VIA   -    MD0100PA00X+054350Y+051800X0200Y         S0      
317GND              VIA   -    MD0100PA00X+054350Y+049800X0200Y    R180 S0      
317GND              VIA   -    M      A01X+054650Y+049800X0200Y    R180 S2      
017GND              VIA   -    M      A10X+054650Y+049800X0260Y    R180 S2      
017GND                    -    MD0100PA00X+054650Y+049800                       
317GND              VIA   -    M      A01X+049850Y+051800X0200Y         S2      
017GND              VIA   -    M      A10X+049850Y+051800X0260Y         S2      
017GND                    -    MD0100PA00X+049850Y+051800                       
317GND              VIA   -    MD0100PA00X+049550Y+051800X0200Y         S0      
317GND              VIA   -    MD0100PA00X+049550Y+049800X0200Y    R180 S0      
317GND              VIA   -    M      A01X+049850Y+049800X0200Y    R180 S2      
017GND              VIA   -    M      A10X+049850Y+049800X0260Y    R180 S2      
017GND                    -    MD0100PA00X+049850Y+049800                       
317GND              PU2   -3   MD0630PA00X+050878Y+047720X0930Y    R270 S3      
317GND              VIA   -    M      A01X+043702Y+049800X0200Y    R180 S2      
017GND              VIA   -    M      A10X+043702Y+049800X0260Y    R180 S2      
017GND                    -    MD0100PA00X+043702Y+049800                       
317GND              VIA   -    MD0100PA00X+043402Y+049800X0200Y    R180 S0      
317GND              VIA   -    M      A01X+043702Y+051800X0200Y         S2      
017GND              VIA   -    M      A10X+043702Y+051800X0260Y         S2      
017GND                    -    MD0100PA00X+043702Y+051800                       
317GND              VIA   -    MD0100PA00X+043402Y+051800X0200Y         S0      
317GND              VIA   -    M      A01X+038902Y+049800X0200Y    R180 S2      
017GND              VIA   -    M      A10X+038902Y+049800X0260Y    R180 S2      
017GND                    -    MD0100PA00X+038902Y+049800                       
317GND              VIA   -    MD0100PA00X+038602Y+049800X0200Y    R180 S0      
317GND              VIA   -    MD0100PA00X+038602Y+051800X0200Y         S0      
317GND              VIA   -    M      A01X+038902Y+051800X0200Y         S2      
017GND              VIA   -    M      A10X+038902Y+051800X0260Y         S2      
017GND                    -    MD0100PA00X+038902Y+051800                       
317GND              VIA   -    M      A01X+034102Y+049800X0200Y    R180 S2      
017GND              VIA   -    M      A10X+034102Y+049800X0260Y    R180 S2      
017GND                    -    MD0100PA00X+034102Y+049800                       
317GND              VIA   -    MD0100PA00X+033802Y+049800X0200Y    R180 S0      
317GND              VIA   -    MD0100PA00X+033802Y+051800X0200Y         S0      
317GND              VIA   -    M      A01X+034102Y+051800X0200Y         S2      
017GND              VIA   -    M      A10X+034102Y+051800X0260Y         S2      
017GND                    -    MD0100PA00X+034102Y+051800                       
317GND              PU3   -3   MD0630PA00X+035130Y+047720X0930Y    R270 S3      
317GND              VIA   -    M      A01X+027954Y+049800X0200Y    R180 S2      
017GND              VIA   -    M      A10X+027954Y+049800X0260Y    R180 S2      
017GND                    -    MD0100PA00X+027954Y+049800                       
317GND              VIA   -    MD0100PA00X+027654Y+049800X0200Y    R180 S0      
317GND              VIA   -    M      A01X+027954Y+051800X0200Y         S2      
017GND              VIA   -    M      A10X+027954Y+051800X0260Y         S2      
017GND                    -    MD0100PA00X+027954Y+051800                       
317GND              VIA   -    MD0100PA00X+027654Y+051800X0200Y         S0      
317GND              VIA   -    M      A01X+023154Y+049800X0200Y    R180 S2      
017GND              VIA   -    M      A10X+023154Y+049800X0260Y    R180 S2      
017GND                    -    MD0100PA00X+023154Y+049800                       
317GND              VIA   -    MD0100PA00X+022854Y+049800X0200Y    R180 S0      
317GND              VIA   -    MD0100PA00X+022854Y+051800X0200Y         S0      
317GND              VIA   -    M      A01X+023154Y+051800X0200Y         S2      
017GND              VIA   -    M      A10X+023154Y+051800X0260Y         S2      
017GND                    -    MD0100PA00X+023154Y+051800                       
317GND              VIA   -    M      A01X+018354Y+049800X0200Y    R180 S2      
017GND              VIA   -    M      A10X+018354Y+049800X0260Y    R180 S2      
017GND                    -    MD0100PA00X+018354Y+049800                       
317GND              VIA   -    MD0100PA00X+018054Y+049800X0200Y    R180 S0      
317GND              VIA   -    MD0100PA00X+018054Y+051800X0200Y         S0      
317GND              VIA   -    M      A01X+018354Y+051800X0200Y         S2      
017GND              VIA   -    M      A10X+018354Y+051800X0260Y         S2      
017GND                    -    MD0100PA00X+018354Y+051800                       
317GND              PU4   -3   MD0630PA00X+019382Y+047720X0930Y    R270 S3      
317GND              VIA   -    MD0100PA00X+053878Y+044502X0200Y         S0      
317GND              VIA   -    MD0100PA00X+038130Y+044502X0200Y         S0      
317GND              VIA   -    MD0100PA00X+022382Y+044502X0200Y         S0      
317GND              J7    -S3  MD0340PA00X+003378Y+032472X0500Y    R270 S3      
317GND              VIA   -    MD0100PA00X+055453Y+030598X0200Y         S0      
317GND              VIA   -    MD0100PA00X+055148Y+030550X0200Y         S0      
317GND              VIA   -    MD0100PA00X+052303Y+030598X0200Y         S0      
317GND              VIA   -    MD0100PA00X+054248Y+030550X0200Y         S0      
317GND              VIA   -    MD0100PA00X+053348Y+030550X0200Y         S0      
317GND              VIA   -    MD0100PA00X+036555Y+030598X0200Y         S0      
317GND              VIA   -    MD0100PA00X+039705Y+030598X0200Y         S0      
317GND              VIA   -    MD0100PA00X+039300Y+030500X0200Y         S0      
317GND              VIA   -    MD0100PA00X+038398Y+030500X0200Y         S0      
317GND              VIA   -    MD0100PA00X+037548Y+030500X0200Y         S0      
317GND              VIA   -    MD0100PA00X+023957Y+030598X0200Y         S0      
317GND              VIA   -    MD0100PA00X+023598Y+030500X0200Y         S0      
317GND              VIA   -    MD0100PA00X+022698Y+030500X0200Y         S0      
317GND              VIA   -    MD0100PA00X+021850Y+030500X0200Y         S0      
317GND              VIA   -    MD0100PA00X+020807Y+030598X0200Y         S0      
317GND              PU2   -5   MD0830PA00X+050878Y+027720X1230Y    R270 S3      
317GND              PU2   -4   MD0830PA00X+049378Y+027720X1230Y    R270 S3      
317GND              PU3   -5   MD0830PA00X+035130Y+027720X1230Y    R270 S3      
317GND              PU3   -4   MD0830PA00X+033630Y+027720X1230Y    R270 S3      
317GND              PU4   -5   MD0830PA00X+019382Y+027720X1230Y    R270 S3      
317GND              PU4   -4   MD0830PA00X+017882Y+027720X1230Y    R270 S3      
317GND              J7    -P4  MD0410PA00X+003878Y+025929X0580Y    R270 S3      
317GND              J7    -P3  MD0410PA00X+003878Y+025260X0580Y    R270 S3      
317GND              VIA   -    MD0100PA00X+055200Y+024700X0200Y         S0      
317GND              VIA   -    MD0100PA00X+055200Y+024350X0200Y         S0      
317GND              VIA   -    MD0100PA00X+055550Y+023600X0200Y         S0      
317GND              VIA   -    MD0100PA00X+055550Y+023900X0200Y         S0      
317GND              VIA   -    MD0100PA00X+039850Y+024250X0200Y         S0      
317GND              VIA   -    M      A01X+039850Y+024700X0200Y         S2      
017GND              VIA   -    M      A10X+039850Y+024700X0260Y         S2      
017GND                    -    MD0100PA00X+039850Y+024700                       
317GND              VIA   -    M      A01X+040200Y+023800X0200Y         S2      
017GND              VIA   -    M      A10X+040200Y+023800X0260Y         S2      
017GND                    -    MD0100PA00X+040200Y+023800                       
317GND              VIA   -    MD0100PA00X+040200Y+023500X0200Y         S0      
317GND              VIA   -    MD0100PA00X+024250Y+024750X0200Y         S0      
317GND              VIA   -    MD0100PA00X+024250Y+024300X0200Y         S0      
317GND              VIA   -    M      A01X+024600Y+023850X0200Y         S2      
017GND              VIA   -    M      A10X+024600Y+023850X0260Y         S2      
017GND                    -    MD0100PA00X+024600Y+023850                       
317GND              VIA   -    MD0100PA00X+024600Y+023550X0200Y         S0      
317GND              J7    -P2  MD0410PA00X+003878Y+023929X0580Y    R270 S3      
317GND              J7    -P1  MD0410PA00X+003878Y+023260X0580Y    R270 S3      
317GND              VIA   -    MD0100PA00X+066900Y+019550X0200Y         S0      
317GND              VIA   -    MD0100PA00X+066900Y+019800X0200Y         S0      
317GND              VIA   -    MD0100PA00X+066900Y+020300X0200Y         S0      
317GND              VIA   -    MD0100PA00X+066900Y+020550X0200Y         S0      
317GND              VIA   -    MD0100PA00X+069050Y+019550X0200Y         S0      
317GND              VIA   -    MD0100PA00X+069050Y+019800X0200Y         S0      
317GND              VIA   -    MD0100PA00X+069050Y+020300X0200Y         S0      
317GND              VIA   -    MD0100PA00X+069050Y+020550X0200Y         S0      
317GND              VIA   -    MD0100PA00X+062600Y+019550X0200Y         S0      
317GND              VIA   -    MD0100PA00X+062600Y+019800X0200Y         S0      
317GND              VIA   -    MD0100PA00X+062600Y+020300X0200Y         S0      
317GND              VIA   -    MD0100PA00X+062600Y+020550X0200Y         S0      
317GND              VIA   -    MD0100PA00X+064750Y+019550X0200Y         S0      
317GND              VIA   -    MD0100PA00X+064750Y+019800X0200Y         S0      
317GND              VIA   -    MD0100PA00X+064750Y+020300X0200Y         S0      
317GND              VIA   -    MD0100PA00X+064750Y+020550X0200Y         S0      
317GND              VIA   -    MD0100PA00X+060450Y+019550X0200Y         S0      
317GND              VIA   -    MD0100PA00X+060450Y+019800X0200Y         S0      
317GND              VIA   -    MD0100PA00X+060450Y+020300X0200Y         S0      
317GND              VIA   -    MD0100PA00X+060450Y+020550X0200Y         S0      
317GND              VIA   -    MD0100PA00X+042600Y+019600X0200Y         S0      
317GND              VIA   -    MD0100PA00X+042600Y+019850X0200Y         S0      
317GND              VIA   -    MD0100PA00X+042600Y+020350X0200Y         S0      
317GND              VIA   -    MD0100PA00X+042600Y+020600X0200Y         S0      
317GND              VIA   -    MD0100PA00X+040450Y+019600X0200Y         S0      
317GND              VIA   -    MD0100PA00X+040450Y+019850X0200Y         S0      
317GND              VIA   -    MD0100PA00X+040450Y+020350X0200Y         S0      
317GND              VIA   -    MD0100PA00X+040450Y+020600X0200Y         S0      
317GND              VIA   -    MD0100PA00X+038300Y+019600X0200Y         S0      
317GND              VIA   -    MD0100PA00X+038300Y+019850X0200Y         S0      
317GND              VIA   -    MD0100PA00X+038300Y+020350X0200Y         S0      
317GND              VIA   -    MD0100PA00X+038300Y+020600X0200Y         S0      
317GND              VIA   -    MD0100PA00X+036150Y+019600X0200Y         S0      
317GND              VIA   -    MD0100PA00X+036150Y+019850X0200Y         S0      
317GND              VIA   -    MD0100PA00X+036150Y+020350X0200Y         S0      
317GND              VIA   -    MD0100PA00X+036150Y+020600X0200Y         S0      
317GND              VIA   -    MD0100PA00X+034000Y+019600X0200Y         S0      
317GND              VIA   -    MD0100PA00X+034000Y+019850X0200Y         S0      
317GND              VIA   -    MD0100PA00X+034000Y+020350X0200Y         S0      
317GND              VIA   -    MD0100PA00X+034000Y+020600X0200Y         S0      
317GND              VIA   -    MD0100PA00X+031850Y+019600X0200Y         S0      
317GND              VIA   -    MD0100PA00X+031850Y+019850X0200Y         S0      
317GND              VIA   -    MD0100PA00X+031850Y+020350X0200Y         S0      
317GND              VIA   -    MD0100PA00X+031850Y+020600X0200Y         S0      
317GND              VIA   -    MD0100PA00X+029700Y+019600X0200Y         S0      
317GND              VIA   -    MD0100PA00X+029700Y+019850X0200Y         S0      
317GND              VIA   -    MD0100PA00X+029700Y+020350X0200Y         S0      
317GND              VIA   -    MD0100PA00X+029700Y+020600X0200Y         S0      
317GND              J2    -P3_1MD0402PA00X+036675Y+015968X0602Y         S3      
317GND              J2    -P3_2MD0402PA00X+036675Y+014968X0602Y         S3      
317GND              J2    -P3_3MD0402PA00X+036675Y+013968X0602Y         S3      
317GND              J2    -P3_5MD0402PA00X+037675Y+015968X0602Y         S3      
317GND              J2    -P3_6MD0402PA00X+037675Y+014968X0602Y         S3      
317GND              J2    -P3_7MD0402PA00X+037675Y+013968X0602Y         S3      
317GND              J2    -P2_1MD0402PA00X+033175Y+015968X0602Y         S3      
317GND              J2    -P2_2MD0402PA00X+033175Y+014968X0602Y         S3      
317GND              J2    -P2_3MD0402PA00X+033175Y+013968X0602Y         S3      
317GND              J2    -P2_5MD0402PA00X+034175Y+015968X0602Y         S3      
317GND              J2    -P2_6MD0402PA00X+034175Y+014968X0602Y         S3      
317GND              J2    -P2_7MD0402PA00X+034175Y+013968X0602Y         S3      
317GND              J2    -P1_1MD0402PA00X+029675Y+015968X0602Y0602     S3      
317GND              J2    -P1_2MD0402PA00X+029675Y+014968X0602Y         S3      
317GND              J2    -P1_3MD0402PA00X+029675Y+013968X0602Y         S3      
317GND              J2    -P1_5MD0402PA00X+030675Y+015968X0602Y         S3      
317GND              J2    -P1_6MD0402PA00X+030675Y+014968X0602Y         S3      
317GND              J2    -P1_7MD0402PA00X+030675Y+013968X0602Y         S3      
317GND              J2    -P3_4MD0402PA00X+036675Y+012968X0602Y         S3      
317GND              J2    -P3_8MD0402PA00X+037675Y+012968X0602Y         S3      
317GND              J2    -P2_4MD0402PA00X+033175Y+012968X0602Y         S3      
317GND              J2    -P2_8MD0402PA00X+034175Y+012968X0602Y         S3      
317GND              J2    -P1_4MD0402PA00X+029675Y+012968X0602Y         S3      
317GND              J2    -P1_8MD0402PA00X+030675Y+012968X0602Y         S3      
317GND              H4    -1   MD1190PA00X+051181Y+004724X3940Y    R270 S3      
317GND              H16   -1   MD1190PA00X+011811Y+004724X3940Y    R270 S3      
317GND              J1    -B3  MD0402PA00X+081256Y+013941X0602Y    R270 S3      
317GND              J1    -P3_8MD0402PA00X+085256Y+014941X0602Y    R270 S3      
317GND              J1    -P3_7MD0402PA00X+085256Y+013941X0602Y    R270 S3      
317GND              J1    -P3_6MD0402PA00X+085256Y+012941X0602Y    R270 S3      
317GND              J1    -P3_5MD0402PA00X+085256Y+011941X0602Y    R270 S3      
317GND              J1    -P3_4MD0402PA00X+086256Y+014941X0602Y    R270 S3      
317GND              J1    -P3_3MD0402PA00X+086256Y+013941X0602Y    R270 S3      
317GND              J1    -P3_2MD0402PA00X+086256Y+012941X0602Y    R270 S3      
317GND              J1    -P3_1MD0402PA00X+086256Y+011941X0602Y    R270 S3      
317GND              J1    -P2_8MD0402PA00X+088756Y+014941X0602Y    R270 S3      
317GND              J1    -P2_7MD0402PA00X+088756Y+013941X0602Y    R270 S3      
317GND              J1    -P2_6MD0402PA00X+088756Y+012941X0602Y    R270 S3      
317GND              J1    -P2_5MD0402PA00X+088756Y+011941X0602Y    R270 S3      
317GND              J1    -P2_4MD0402PA00X+089756Y+014941X0602Y    R270 S3      
317GND              J1    -P2_3MD0402PA00X+089756Y+013941X0602Y    R270 S3      
317GND              J1    -P2_2MD0402PA00X+089756Y+012941X0602Y    R270 S3      
317GND              J1    -P2_1MD0402PA00X+089756Y+011941X0602Y    R270 S3      
317GND              J1    -P1_8MD0402PA00X+092256Y+014941X0602Y    R270 S3      
317GND              J1    -P1_7MD0402PA00X+092256Y+013941X0602Y    R270 S3      
317GND              J1    -P1_6MD0402PA00X+092256Y+012941X0602Y    R270 S3      
317GND              J1    -P1_5MD0402PA00X+092256Y+011941X0602Y    R270 S3      
317GND              J1    -P1_4MD0402PA00X+093256Y+014941X0602Y    R270 S3      
317GND              J1    -P1_3MD0402PA00X+093256Y+013941X0602Y    R270 S3      
317GND              J1    -P1_2MD0402PA00X+093256Y+012941X0602Y    R270 S3      
317GND              J1    -P1_1MD0402PA00X+093256Y+011941X0602Y    R270 S3      
317GND              VIA   -    MD0100PA00X+118332Y+012065X0200Y    R090 S0      
317GND              VIA   -    MD0100PA00X+118582Y+012065X0200Y    R090 S0      
317GND              VIA   -    MD0100PA00X+118832Y+012065X0200Y    R090 S0      
317GND              VIA   -    MD0100PA00X+118832Y+012365X0200Y    R090 S0      
317GND              VIA   -    MD0100PA00X+118582Y+012365X0200Y    R090 S0      
317GND              VIA   -    MD0100PA00X+118332Y+012365X0200Y    R090 S0      
317GND              J5    -P3_8MD0402PA00X+122602Y+025693X0602Y         S3      
317GND              J5    -P3_7MD0402PA00X+123602Y+025693X0602Y         S3      
317GND              J5    -P3_6MD0402PA00X+124602Y+025693X0602Y         S3      
317GND              J5    -P3_5MD0402PA00X+125602Y+025693X0602Y         S3      
317GND              J5    -P3_4MD0402PA00X+122602Y+026693X0602Y         S3      
317GND              J5    -P3_3MD0402PA00X+123602Y+026693X0602Y         S3      
317GND              J5    -P3_2MD0402PA00X+124602Y+026693X0602Y         S3      
317GND              J5    -P3_1MD0402PA00X+125602Y+026693X0602Y         S3      
317GND              J5    -P4_8MD0402PA00X+122602Y+022193X0602Y         S3      
317GND              J5    -P4_7MD0402PA00X+123602Y+022193X0602Y         S3      
317GND              J5    -P4_6MD0402PA00X+124602Y+022193X0602Y         S3      
317GND              J5    -P4_5MD0402PA00X+125602Y+022193X0602Y         S3      
317GND              J5    -P4_4MD0402PA00X+122602Y+023193X0602Y         S3      
317GND              J5    -P4_3MD0402PA00X+123602Y+023193X0602Y         S3      
317GND              J5    -P4_2MD0402PA00X+124602Y+023193X0602Y         S3      
317GND              J5    -P4_1MD0402PA00X+125602Y+023193X0602Y         S3      
317GND              H20   -1   M      A01X+124016Y+005748X4000Y    R270 S3      
017GND              H20   -1   M      A10X+124016Y+005748X3940Y    R270 S3      
017GND                    -    MD2520PA00X+124016Y+005748                       
317GND              H18   -1   MD1190PA00X+090551Y+004724X3940Y    R270 S3      
327GND              C73   -2          A10X+070656Y+030550X0198Y0197R180 S2      
327GND              C71   -2          A10X+068856Y+030550X0198Y0197R180 S2      
327GND              D1    -C          A01X+083063Y+032900X0240Y0280R180 S1      
317GND              VIA   -    MD0100PA00X+085050Y+036008X0200Y         S0      
327GND              R33   -1          A10X+084750Y+036008X0198Y0197R090 S2      
327GND              C8    -1          A10X+085300Y+036008X0198Y0197R090 S2      
327GND              PC563 -1          A10X+109334Y+036984X0280Y0320R180 S2      
327GND              U32   -7          A01X+016961Y+023014X0100Y0320R090 S1      
327GND              R5911 -2          A10X+114676Y+016824X0198Y0197R090 S2      
317FRU_WP_N         VIA   -    M      A01X+087500Y+034727X0300Y         S1      
017FRU_WP_N         VIA   -    M      A10X+087500Y+034727X0200Y         S1      
017FRU_WP_N               -    MD0100PA00X+087500Y+034727                       
327FRU_WP_N         U10   -7          A10X+087500Y+033890X0220Y0680     S2      
327FRU_WP_N         R36   -2   M      A10X+087400Y+035292X0198Y0197R090 S2      
327FRU_WP_N         R37   -1          A10X+087800Y+035292X0198Y0197R270 S2      
317FRU_ADDR2        VIA   -    M      A01X+087000Y+031279X0300Y         S1      
017FRU_ADDR2        VIA   -    M      A10X+087000Y+031279X0200Y         S1      
017FRU_ADDR2              -    MD0100PA00X+087000Y+031279                       
327FRU_ADDR2        R43   -2          A10X+087000Y+029708X0198Y0197R270 S2      
327FRU_ADDR2        R38   -2   M      A10X+087000Y+031008X0198Y0197R270 S2      
327FRU_ADDR2        U10   -3          A10X+087000Y+031810X0220Y0680     S2      
317m0133            VIA   -    MD0100PA00X+094058Y+030400X0200Y         S0      
327m0133            R5    -2          A10X+094058Y+030650X0198Y0197R180 S2      
317m0133            VIA   -    M      A01X+075400Y+035696X0200Y         S2      
017m0133            VIA   -    M      A10X+075400Y+035696X0260Y         S2      
017m0133                  -    MD0100PA00X+075400Y+035696                       
327m0133            U25   -19         A10X+076028Y+035696X0160Y0440R090 S2      
327m0134            R4    -2          A10X+093800Y+036108X0198Y0197R270 S2      
317m0134            VIA   -    M      A01X+093552Y+036108X0300Y         S1      
017m0134            VIA   -    M      A10X+093552Y+036108X0200Y         S1      
017m0134                  -    MD0100PA00X+093552Y+036108                       
317m0134            VIA   -    MD0100PA00X+075400Y+035350X0200Y         S0      
327m0134            U25   -18         A10X+076028Y+035440X0160Y0440R090 S2      
327m0135            VIA   -    M      A10X+093250Y+030538X0260Y         S2      
327m0135            U1    -7          A10X+093592Y+032260X0140Y0560R180 S2      
327m0135            R7    -2   M      A10X+093762Y+031538X0198Y0197     S2      
327m0135            R2    -1   M      A10X+093762Y+031088X0198Y0197R180 S2      
327m0135            R5    -1          A10X+093742Y+030650X0198Y0197R180 S2      
327m0136            VIA   -    M      A10X+094255Y+035792X0260Y         S2      
327m0136            U1    -2          A10X+093592Y+034017X0140Y0560R180 S2      
327m0136            R4    -1          A10X+093800Y+035792X0198Y0197R270 S2      
327m0136            R1    -1   M      A10X+093812Y+035238X0198Y0197R180 S2      
327m0136            R6    -2   M      A10X+093812Y+034788X0198Y0197     S2      
C                                                                               
C  ****************************************                                     
C      DUMMY NET PINS & VIAS ON THE BOARD                                       
C  ****************************************                                     
C                                                                               
327N/C              PU7   -35         A01X+114762Y+017556X0120Y0330R270 S1      
327N/C              PU7   -34         A01X+114762Y+017359X0120Y0330R270 S1      
327N/C              PU7   -28         A01X+114762Y+016178X0120Y0330R270 S1      
327N/C              PU7   -27         A01X+114762Y+015981X0120Y0330R270 S1      
327N/C              PU7   -25         A01X+114762Y+015587X0120Y0330R270 S1      
327N/C              PU7   -40         A01X+113896Y+018028X0120Y0330     S1      
327N/C              PU7   -33         A01X+114762Y+017162X0120Y0330R270 S1      
327N/C              PU7   -37         A01X+114487Y+018028X0120Y0330     S1      
327N/C              PU7   -26         A01X+114762Y+015784X0120Y0330R270 S1      
327N/C              PU7   -36         A01X+114762Y+017753X0120Y0330R270 S1      
327N/C                    -           A10X+115535Y+056114X0390Y         S2      
327N/C                    -           A10X+095455Y+007725X0390Y         S2      
327N/C                    -           A10X+021100Y+002600X0390Y         S2      
327N/C                    -           A01X+117682Y+055539X0390Y         S1      
327N/C                    -           A01X+089211Y+008112X0390Y         S1      
327N/C                    -           A01X+020100Y+002050X0390Y         S1      
317N/C              J7    -H1   D0870UA00X+001992Y+036772X0870Y    R270 S3      
317N/C              J7    -H2   D0870UA00X+001992Y+021417X0870Y    R270 S3      
317N/C              J5    -SCR_ D1260UA00X+122602Y+039943X2560Y2560     S3      
317N/C              J5    -SCR_ D1260UA00X+122602Y+017443X2560Y2560     S3      
317N/C              J2    -SCR_ D1260UA00X+024925Y+012968X2560Y2560     S3      
317N/C              J2    -SCR_ D1260UA00X+052925Y+012968X2560Y2560     S3      
317N/C              J1    -SCR_ D1260UA00X+098006Y+014941X2560Y2560R270 S3      
317N/C              J1    -SCR_ D1260UA00X+066506Y+014941X2560Y2560R270 S3      
317N/C              H23   -1    D1250UA00X+087751Y+055862X1250Y         S3      
317N/C              H22   -1    D1250UA00X+096446Y+001695X1250Y         S3      
317N/C              H21   -1    D1250UA00X+017500Y+010050X1250Y         S3      
317N/C              J15   -SCR_ D1560UA00X+008280Y+009972X2370Y2370R270 S3      
317N/C              J15   -H1   D1560UA00X+010886Y+009972X1560Y    R270 S3      
317N/C              J15   -H2   D1560UA00X+006063Y+009972X1560Y    R270 S3      
317N/C              J14   -SCR_ D1560UA00X+008280Y+048220X2370Y2370R270 S3      
317N/C              J14   -H1   D1560UA00X+010886Y+048220X1560Y    R270 S3      
317N/C              J14   -H2   D1560UA00X+006063Y+048220X1560Y    R270 S3      
327N/C              PU7   -16         A01X+112518Y+015312X0120Y0330     S1      
327N/C              PU7   -15         A01X+112321Y+015312X0120Y0330     S1      
327N/C              PU1   -18         A01X+104938Y+014928X0110Y0280     S1      
327N/C              PU1   -30         A01X+105204Y+017359X0110Y0280R270 S1      
327N/C              PU1   -31         A01X+104938Y+017625X0110Y0280     S1      
327N/C              PU1   -32         A01X+104741Y+017615X0110Y0300     S1      
327N/C              PU1   -22         A01X+105194Y+015785X0110Y0300R270 S1      
C                                                                               
C  End-of-Job                                                                   
C                                                                               
999                                                                             
